FILE_TYPE = MACRO_DRAWING;
SET COLOR_WIRE YELLOW;
SET COLOR_PROP MONO;
SET COLOR_DOT WHITE;
SET COLOR_ARC YELLOW;
SET COLOR_BODY GREEN;
SET COLOR_NOTE MONO;
SET PROP_DISPLAY VALUE;
SET PAGE_NUMBER P191;
FORCEADD OFFPAGE..4
(-2450 4225);
FORCEPROP 2 LAST $XR2 198 
J 0
(-2024 4225);
DISPLAY 0.638298 (-2024 4225);
PAINT MONO (-2024 4225);
FORCEPROP 2 LAST $XR1 161 
J 0
(-2144 4225);
DISPLAY 0.638298 (-2144 4225);
PAINT MONO (-2144 4225);
FORCEPROP 2 LAST $XR0 181 
J 0
(-2264 4225);
DISPLAY 0.638298 (-2264 4225);
PAINT MONO (-2264 4225);
FORCEPROP 2 LAST CDS_LIB mstr_standard
J 0
(-2450 4225);
PAINT ORANGE (-2450 4225);
DISPLAY INVISIBLE (-2450 4225);
FORCEPROP 1 LAST OFFPAGE TRUE
J 0
(-2125 4100);
DISPLAY 1.170213 (-2125 4100);
PAINT GREEN (-2125 4100);
DISPLAY INVISIBLE (-2125 4100);
FORCEPROP 1 LAST COMMENT_BODY TRUE
J 0
(-2475 4125);
DISPLAY 1.170213 (-2475 4125);
PAINT GREEN (-2475 4125);
DISPLAY INVISIBLE (-2475 4125);
FORCEPROP 2 LAST PATH I1
J 0
(-1800 4275);
DISPLAY 1.021277 (-1800 4275);
PAINT ORANGE (-1800 4275);
DISPLAY INVISIBLE (-1800 4275);
FORCEADD OFFPAGE..4
R 2
(-6425 2125);
FORCEPROP 2 LAST $XR5 239 
J 0
(-7277 2125);
DISPLAY 0.638298 (-7277 2125);
PAINT MONO (-7277 2125);
FORCEPROP 2 LAST $XR4 237 
J 0
(-7157 2125);
DISPLAY 0.638298 (-7157 2125);
PAINT MONO (-7157 2125);
FORCEPROP 2 LAST $XR3 196 
J 0
(-7037 2125);
DISPLAY 0.638298 (-7037 2125);
PAINT MONO (-7037 2125);
FORCEPROP 2 LAST $XR2 189 
J 0
(-6917 2125);
DISPLAY 0.638298 (-6917 2125);
PAINT MONO (-6917 2125);
FORCEPROP 2 LAST $XR1 101 
J 0
(-6797 2125);
DISPLAY 0.638298 (-6797 2125);
PAINT MONO (-6797 2125);
FORCEPROP 2 LAST $XR0 240 
J 0
(-6677 2125);
DISPLAY 0.638298 (-6677 2125);
PAINT MONO (-6677 2125);
FORCEPROP 2 LAST CDS_LIB mstr_standard
J 0
(-6425 2125);
PAINT ORANGE (-6425 2125);
DISPLAY INVISIBLE (-6425 2125);
FORCEPROP 1 LAST OFFPAGE TRUE
J 2
(-6750 2000);
DISPLAY 1.170213 (-6750 2000);
PAINT GREEN (-6750 2000);
DISPLAY INVISIBLE (-6750 2000);
FORCEPROP 1 LAST COMMENT_BODY TRUE
J 2
(-6400 2025);
DISPLAY 1.170213 (-6400 2025);
PAINT GREEN (-6400 2025);
DISPLAY INVISIBLE (-6400 2025);
FORCEPROP 2 LAST PATH I102
J 0
(-6375 2200);
DISPLAY 1.021277 (-6375 2200);
PAINT ORANGE (-6375 2200);
DISPLAY INVISIBLE (-6375 2200);
FORCEADD OFFPAGE..4
R 2
(-6425 3225);
FORCEPROP 2 LAST $XR0 92 
J 0
(-6646 3225);
DISPLAY 0.638298 (-6646 3225);
PAINT MONO (-6646 3225);
FORCEPROP 2 LAST CDS_LIB mstr_standard
J 0
(-6425 3225);
PAINT ORANGE (-6425 3225);
DISPLAY INVISIBLE (-6425 3225);
FORCEPROP 1 LAST OFFPAGE TRUE
J 2
(-6750 3100);
DISPLAY 1.170213 (-6750 3100);
PAINT GREEN (-6750 3100);
DISPLAY INVISIBLE (-6750 3100);
FORCEPROP 1 LAST COMMENT_BODY TRUE
J 2
(-6400 3125);
DISPLAY 1.170213 (-6400 3125);
PAINT GREEN (-6400 3125);
DISPLAY INVISIBLE (-6400 3125);
FORCEPROP 2 LAST PATH I115
J 0
(-6375 3300);
DISPLAY 1.021277 (-6375 3300);
PAINT ORANGE (-6375 3300);
DISPLAY INVISIBLE (-6375 3300);
FORCEADD OFFPAGE..2
R 2
(-6425 4025);
FORCEPROP 2 LAST $XR0 120 
J 0
(-6680 4025);
DISPLAY 0.638298 (-6680 4025);
PAINT MONO (-6680 4025);
FORCEPROP 2 LAST CDS_LIB mstr_standard
J 0
(-6425 4025);
PAINT ORANGE (-6425 4025);
DISPLAY INVISIBLE (-6425 4025);
FORCEPROP 1 LAST OFFPAGE TRUE
J 2
(-6750 3900);
DISPLAY 1.170213 (-6750 3900);
PAINT GREEN (-6750 3900);
DISPLAY INVISIBLE (-6750 3900);
FORCEPROP 1 LAST COMMENT_BODY TRUE
J 2
(-6380 3930);
DISPLAY 1.170213 (-6380 3930);
PAINT GREEN (-6380 3930);
DISPLAY INVISIBLE (-6380 3930);
FORCEPROP 2 LAST PATH I118
J 0
(-6375 4100);
DISPLAY 1.021277 (-6375 4100);
PAINT ORANGE (-6375 4100);
DISPLAY INVISIBLE (-6375 4100);
FORCEADD OFFPAGE..2
R 2
(-6425 3975);
FORCEPROP 2 LAST $XR2 144 
J 0
(-6920 3975);
DISPLAY 0.638298 (-6920 3975);
PAINT MONO (-6920 3975);
FORCEPROP 2 LAST $XR1 118 
J 0
(-6800 3975);
DISPLAY 0.638298 (-6800 3975);
PAINT MONO (-6800 3975);
FORCEPROP 2 LAST $XR0 133 
J 0
(-6680 3975);
DISPLAY 0.638298 (-6680 3975);
PAINT MONO (-6680 3975);
FORCEPROP 2 LAST CDS_LIB mstr_standard
J 0
(-6425 3975);
PAINT ORANGE (-6425 3975);
DISPLAY INVISIBLE (-6425 3975);
FORCEPROP 1 LAST OFFPAGE TRUE
J 2
(-6750 3850);
DISPLAY 1.170213 (-6750 3850);
PAINT GREEN (-6750 3850);
DISPLAY INVISIBLE (-6750 3850);
FORCEPROP 1 LAST COMMENT_BODY TRUE
J 2
(-6380 3880);
DISPLAY 1.170213 (-6380 3880);
PAINT GREEN (-6380 3880);
DISPLAY INVISIBLE (-6380 3880);
FORCEPROP 2 LAST PATH I120
J 0
(-6375 4050);
DISPLAY 1.021277 (-6375 4050);
PAINT ORANGE (-6375 4050);
DISPLAY INVISIBLE (-6375 4050);
FORCEADD OFFPAGE..4
R 2
(-6425 3675);
FORCEPROP 2 LAST $XR0 92 
J 0
(-6676 3675);
DISPLAY 0.638298 (-6676 3675);
PAINT MONO (-6676 3675);
FORCEPROP 2 LAST CDS_LIB mstr_standard
J 0
(-6425 3675);
PAINT ORANGE (-6425 3675);
DISPLAY INVISIBLE (-6425 3675);
FORCEPROP 1 LAST OFFPAGE TRUE
J 2
(-6750 3550);
DISPLAY 0.872340 (-6750 3550);
PAINT GREEN (-6750 3550);
DISPLAY INVISIBLE (-6750 3550);
FORCEPROP 1 LAST COMMENT_BODY TRUE
J 2
(-6400 3575);
DISPLAY 0.872340 (-6400 3575);
PAINT GREEN (-6400 3575);
DISPLAY INVISIBLE (-6400 3575);
FORCEPROP 2 LAST PATH I125
J 0
(-6375 3750);
DISPLAY 1.021277 (-6375 3750);
PAINT ORANGE (-6375 3750);
DISPLAY INVISIBLE (-6375 3750);
FORCEADD OFFPAGE..4
R 2
(-6425 4275);
FORCEPROP 2 LAST $XR3 247 
J 0
(-7067 4275);
DISPLAY 0.638298 (-7067 4275);
PAINT MONO (-7067 4275);
FORCEPROP 2 LAST $XR2 139 
J 0
(-6947 4275);
DISPLAY 0.638298 (-6947 4275);
PAINT MONO (-6947 4275);
FORCEPROP 2 LAST $XR1 136 
J 0
(-6827 4275);
DISPLAY 0.638298 (-6827 4275);
PAINT MONO (-6827 4275);
FORCEPROP 2 LAST $XR0 119 
J 0
(-6707 4275);
DISPLAY 0.638298 (-6707 4275);
PAINT MONO (-6707 4275);
FORCEPROP 2 LAST CDS_LIB mstr_standard
J 0
(-6425 4275);
PAINT ORANGE (-6425 4275);
DISPLAY INVISIBLE (-6425 4275);
FORCEPROP 1 LAST OFFPAGE TRUE
J 2
(-6750 4150);
DISPLAY 1.170213 (-6750 4150);
PAINT GREEN (-6750 4150);
DISPLAY INVISIBLE (-6750 4150);
FORCEPROP 1 LAST COMMENT_BODY TRUE
J 2
(-6400 4175);
DISPLAY 1.170213 (-6400 4175);
PAINT GREEN (-6400 4175);
DISPLAY INVISIBLE (-6400 4175);
FORCEPROP 2 LAST PATH I127
J 0
(-6375 4350);
DISPLAY 1.021277 (-6375 4350);
PAINT ORANGE (-6375 4350);
DISPLAY INVISIBLE (-6375 4350);
FORCEADD OFFPAGE..2
R 2
(-6425 4325);
FORCEPROP 2 LAST $XR3 247 
J 0
(-7040 4325);
DISPLAY 0.638298 (-7040 4325);
PAINT MONO (-7040 4325);
FORCEPROP 2 LAST $XR2 144 
J 0
(-6920 4325);
DISPLAY 0.638298 (-6920 4325);
PAINT MONO (-6920 4325);
FORCEPROP 2 LAST $XR1 118 
J 0
(-6800 4325);
DISPLAY 0.638298 (-6800 4325);
PAINT MONO (-6800 4325);
FORCEPROP 2 LAST $XR0 133 
J 0
(-6680 4325);
DISPLAY 0.638298 (-6680 4325);
PAINT MONO (-6680 4325);
FORCEPROP 2 LAST CDS_LIB mstr_standard
J 0
(-6425 4325);
PAINT ORANGE (-6425 4325);
DISPLAY INVISIBLE (-6425 4325);
FORCEPROP 1 LAST OFFPAGE TRUE
J 2
(-6750 4200);
DISPLAY 1.170213 (-6750 4200);
PAINT GREEN (-6750 4200);
DISPLAY INVISIBLE (-6750 4200);
FORCEPROP 1 LAST COMMENT_BODY TRUE
J 2
(-6380 4230);
DISPLAY 1.170213 (-6380 4230);
PAINT GREEN (-6380 4230);
DISPLAY INVISIBLE (-6380 4230);
FORCEPROP 2 LAST PATH I128
J 0
(-6375 4400);
DISPLAY 1.021277 (-6375 4400);
PAINT ORANGE (-6375 4400);
DISPLAY INVISIBLE (-6375 4400);
FORCEADD OFFPAGE..2
R 2
(-6425 4175);
FORCEPROP 2 LAST $XR0 89 
J 0
(-6679 4175);
DISPLAY 0.638298 (-6679 4175);
PAINT MONO (-6679 4175);
FORCEPROP 2 LAST CDS_LIB mstr_standard
J 0
(-6425 4175);
PAINT ORANGE (-6425 4175);
DISPLAY INVISIBLE (-6425 4175);
FORCEPROP 1 LAST OFFPAGE TRUE
J 2
(-6750 4050);
DISPLAY 1.170213 (-6750 4050);
PAINT GREEN (-6750 4050);
DISPLAY INVISIBLE (-6750 4050);
FORCEPROP 1 LAST COMMENT_BODY TRUE
J 2
(-6380 4080);
DISPLAY 1.170213 (-6380 4080);
PAINT GREEN (-6380 4080);
DISPLAY INVISIBLE (-6380 4080);
FORCEPROP 2 LAST PATH I129
J 0
(-6375 4250);
DISPLAY 1.021277 (-6375 4250);
PAINT ORANGE (-6375 4250);
DISPLAY INVISIBLE (-6375 4250);
FORCEADD OFFPAGE..2
R 2
(-6425 1375);
FORCEPROP 2 LAST $XR1 234 
J 0
(-6800 1375);
DISPLAY 0.638298 (-6800 1375);
PAINT MONO (-6800 1375);
FORCEPROP 2 LAST $XR0 233 
J 0
(-6680 1375);
DISPLAY 0.638298 (-6680 1375);
PAINT MONO (-6680 1375);
FORCEPROP 2 LAST CDS_LIB mstr_standard
J 0
(-6425 1375);
PAINT ORANGE (-6425 1375);
DISPLAY INVISIBLE (-6425 1375);
FORCEPROP 1 LAST OFFPAGE TRUE
J 2
(-6750 1250);
DISPLAY 1.170213 (-6750 1250);
PAINT GREEN (-6750 1250);
DISPLAY INVISIBLE (-6750 1250);
FORCEPROP 1 LAST COMMENT_BODY TRUE
J 2
(-6380 1280);
DISPLAY 1.170213 (-6380 1280);
PAINT GREEN (-6380 1280);
DISPLAY INVISIBLE (-6380 1280);
FORCEPROP 2 LAST PATH I132
J 0
(-6375 1450);
DISPLAY 1.021277 (-6375 1450);
PAINT ORANGE (-6375 1450);
DISPLAY INVISIBLE (-6375 1450);
FORCEADD OFFPAGE..4
R 2
(-6425 1425);
FORCEPROP 2 LAST $XR0 92 
J 0
(-6646 1425);
DISPLAY 0.638298 (-6646 1425);
PAINT MONO (-6646 1425);
FORCEPROP 2 LAST CDS_LIB mstr_standard
J 0
(-6425 1425);
PAINT ORANGE (-6425 1425);
DISPLAY INVISIBLE (-6425 1425);
FORCEPROP 1 LAST OFFPAGE TRUE
J 2
(-6750 1300);
DISPLAY 1.170213 (-6750 1300);
PAINT GREEN (-6750 1300);
DISPLAY INVISIBLE (-6750 1300);
FORCEPROP 1 LAST COMMENT_BODY TRUE
J 2
(-6400 1325);
DISPLAY 1.170213 (-6400 1325);
PAINT GREEN (-6400 1325);
DISPLAY INVISIBLE (-6400 1325);
FORCEPROP 2 LAST PATH I133
J 0
(-6375 1500);
DISPLAY 1.021277 (-6375 1500);
PAINT ORANGE (-6375 1500);
DISPLAY INVISIBLE (-6375 1500);
FORCEADD OFFPAGE..4
R 2
(-6425 1475);
FORCEPROP 2 LAST $XR0 55 
J 0
(-6646 1475);
DISPLAY 0.638298 (-6646 1475);
PAINT MONO (-6646 1475);
FORCEPROP 2 LAST CDS_LIB mstr_standard
J 0
(-6425 1475);
PAINT ORANGE (-6425 1475);
DISPLAY INVISIBLE (-6425 1475);
FORCEPROP 1 LAST OFFPAGE TRUE
J 2
(-6750 1350);
DISPLAY 1.170213 (-6750 1350);
PAINT GREEN (-6750 1350);
DISPLAY INVISIBLE (-6750 1350);
FORCEPROP 1 LAST COMMENT_BODY TRUE
J 2
(-6400 1375);
DISPLAY 1.170213 (-6400 1375);
PAINT GREEN (-6400 1375);
DISPLAY INVISIBLE (-6400 1375);
FORCEPROP 2 LAST PATH I134
J 0
(-6375 1550);
DISPLAY 1.021277 (-6375 1550);
PAINT ORANGE (-6375 1550);
DISPLAY INVISIBLE (-6375 1550);
FORCEADD OFFPAGE..4
(-2450 1275);
FORCEPROP 2 LAST $XR1 133 
J 0
(-2144 1275);
DISPLAY 0.638298 (-2144 1275);
PAINT MONO (-2144 1275);
FORCEPROP 2 LAST $XR0 121 
J 0
(-2264 1275);
DISPLAY 0.638298 (-2264 1275);
PAINT MONO (-2264 1275);
FORCEPROP 2 LAST CDS_LIB mstr_standard
J 0
(-2450 1275);
PAINT ORANGE (-2450 1275);
DISPLAY INVISIBLE (-2450 1275);
FORCEPROP 1 LAST OFFPAGE TRUE
J 0
(-2125 1150);
DISPLAY 1.170213 (-2125 1150);
PAINT GREEN (-2125 1150);
DISPLAY INVISIBLE (-2125 1150);
FORCEPROP 1 LAST COMMENT_BODY TRUE
J 0
(-2475 1175);
DISPLAY 1.170213 (-2475 1175);
PAINT GREEN (-2475 1175);
DISPLAY INVISIBLE (-2475 1175);
FORCEPROP 2 LAST PATH I135
J 0
(-2275 1350);
DISPLAY 1.021277 (-2275 1350);
PAINT ORANGE (-2275 1350);
DISPLAY INVISIBLE (-2275 1350);
FORCEADD OFFPAGE..2
(-2450 1375);
FORCEPROP 2 LAST $XR1 118 
J 0
(-2141 1375);
DISPLAY 0.638298 (-2141 1375);
PAINT MONO (-2141 1375);
FORCEPROP 2 LAST $XR0 156 
J 0
(-2261 1375);
DISPLAY 0.638298 (-2261 1375);
PAINT MONO (-2261 1375);
FORCEPROP 2 LAST CDS_LIB mstr_standard
J 2
(-2450 1375);
PAINT ORANGE (-2450 1375);
DISPLAY INVISIBLE (-2450 1375);
FORCEPROP 1 LAST OFFPAGE TRUE
J 0
(-2125 1250);
DISPLAY 1.170213 (-2125 1250);
PAINT GREEN (-2125 1250);
DISPLAY INVISIBLE (-2125 1250);
FORCEPROP 1 LAST COMMENT_BODY TRUE
J 0
(-2495 1280);
DISPLAY 1.170213 (-2495 1280);
PAINT GREEN (-2495 1280);
DISPLAY INVISIBLE (-2495 1280);
FORCEPROP 2 LAST PATH I136
J 0
(-2275 1450);
DISPLAY 1.021277 (-2275 1450);
PAINT ORANGE (-2275 1450);
DISPLAY INVISIBLE (-2275 1450);
FORCEADD OFFPAGE..4
(-2450 1425);
FORCEPROP 2 LAST $XR1 148 
J 0
(-2144 1425);
DISPLAY 0.638298 (-2144 1425);
PAINT MONO (-2144 1425);
FORCEPROP 2 LAST $XR0 118 
J 0
(-2264 1425);
DISPLAY 0.638298 (-2264 1425);
PAINT MONO (-2264 1425);
FORCEPROP 2 LAST CDS_LIB mstr_standard
J 0
(-2450 1425);
PAINT ORANGE (-2450 1425);
DISPLAY INVISIBLE (-2450 1425);
FORCEPROP 1 LAST OFFPAGE TRUE
J 0
(-2125 1300);
DISPLAY 1.170213 (-2125 1300);
PAINT GREEN (-2125 1300);
DISPLAY INVISIBLE (-2125 1300);
FORCEPROP 1 LAST COMMENT_BODY TRUE
J 0
(-2475 1325);
DISPLAY 1.170213 (-2475 1325);
PAINT GREEN (-2475 1325);
DISPLAY INVISIBLE (-2475 1325);
FORCEPROP 2 LAST PATH I137
J 0
(-2275 1500);
DISPLAY 1.021277 (-2275 1500);
PAINT ORANGE (-2275 1500);
DISPLAY INVISIBLE (-2275 1500);
FORCEADD OFFPAGE..4
(-2450 2075);
FORCEPROP 2 LAST $XR0 189 
J 0
(-2264 2075);
DISPLAY 0.638298 (-2264 2075);
PAINT MONO (-2264 2075);
FORCEPROP 2 LAST CDS_LIB mstr_standard
J 0
(-2450 2075);
PAINT ORANGE (-2450 2075);
DISPLAY INVISIBLE (-2450 2075);
FORCEPROP 1 LAST OFFPAGE TRUE
J 0
(-2125 1950);
DISPLAY 1.170213 (-2125 1950);
PAINT GREEN (-2125 1950);
DISPLAY INVISIBLE (-2125 1950);
FORCEPROP 1 LAST COMMENT_BODY TRUE
J 0
(-2475 1975);
DISPLAY 1.170213 (-2475 1975);
PAINT GREEN (-2475 1975);
DISPLAY INVISIBLE (-2475 1975);
FORCEPROP 2 LAST PATH I139
J 0
(-2275 2150);
DISPLAY 1.021277 (-2275 2150);
PAINT ORANGE (-2275 2150);
DISPLAY INVISIBLE (-2275 2150);
FORCEADD OFFPAGE..3
(-2450 2525);
FORCEPROP 2 LAST $XR2 184 
J 0
(-2236 2489);
DISPLAY 0.638298 (-2236 2489);
PAINT MONO (-2236 2489);
FORCEPROP 2 LAST $XR1 167 
J 0
(-2116 2525);
DISPLAY 0.638298 (-2116 2525);
PAINT MONO (-2116 2525);
FORCEPROP 2 LAST $XR0 164 
J 0
(-2236 2525);
DISPLAY 0.638298 (-2236 2525);
PAINT MONO (-2236 2525);
FORCEPROP 2 LAST CDS_LIB mstr_standard
J 0
(-2450 2525);
PAINT ORANGE (-2450 2525);
DISPLAY INVISIBLE (-2450 2525);
FORCEPROP 1 LAST OFFPAGE TRUE
J 0
(-2125 2400);
DISPLAY 1.170213 (-2125 2400);
PAINT GREEN (-2125 2400);
DISPLAY INVISIBLE (-2125 2400);
FORCEPROP 1 LAST COMMENT_BODY TRUE
J 0
(-2500 2425);
DISPLAY 1.170213 (-2500 2425);
PAINT GREEN (-2500 2425);
DISPLAY INVISIBLE (-2500 2425);
FORCEPROP 2 LAST PATH I141
J 0
(-2250 2600);
DISPLAY 1.021277 (-2250 2600);
PAINT ORANGE (-2250 2600);
DISPLAY INVISIBLE (-2250 2600);
FORCEADD OFFPAGE..4
(-2450 2825);
FORCEPROP 2 LAST $XR0 118 
J 0
(-2264 2825);
DISPLAY 0.638298 (-2264 2825);
PAINT MONO (-2264 2825);
FORCEPROP 2 LAST CDS_LIB mstr_standard
J 0
(-2450 2825);
PAINT ORANGE (-2450 2825);
DISPLAY INVISIBLE (-2450 2825);
FORCEPROP 1 LAST OFFPAGE TRUE
J 0
(-2125 2700);
DISPLAY 1.170213 (-2125 2700);
PAINT GREEN (-2125 2700);
DISPLAY INVISIBLE (-2125 2700);
FORCEPROP 1 LAST COMMENT_BODY TRUE
J 0
(-2475 2725);
DISPLAY 1.170213 (-2475 2725);
PAINT GREEN (-2475 2725);
DISPLAY INVISIBLE (-2475 2725);
FORCEPROP 2 LAST PATH I142
J 0
(-2275 2900);
DISPLAY 1.021277 (-2275 2900);
PAINT ORANGE (-2275 2900);
DISPLAY INVISIBLE (-2275 2900);
FORCEADD OFFPAGE..4
(-2450 2975);
FORCEPROP 2 LAST $XR1 89 
J 0
(-2144 2975);
DISPLAY 0.638298 (-2144 2975);
PAINT MONO (-2144 2975);
FORCEPROP 2 LAST $XR0 120 
J 0
(-2264 2975);
DISPLAY 0.638298 (-2264 2975);
PAINT MONO (-2264 2975);
FORCEPROP 2 LAST CDS_LIB mstr_standard
J 0
(-2450 2975);
PAINT ORANGE (-2450 2975);
DISPLAY INVISIBLE (-2450 2975);
FORCEPROP 1 LAST OFFPAGE TRUE
J 0
(-2125 2850);
DISPLAY 1.170213 (-2125 2850);
PAINT GREEN (-2125 2850);
DISPLAY INVISIBLE (-2125 2850);
FORCEPROP 1 LAST COMMENT_BODY TRUE
J 0
(-2475 2875);
DISPLAY 1.170213 (-2475 2875);
PAINT GREEN (-2475 2875);
DISPLAY INVISIBLE (-2475 2875);
FORCEPROP 2 LAST PATH I143
J 0
(-2275 3050);
DISPLAY 1.021277 (-2275 3050);
PAINT ORANGE (-2275 3050);
DISPLAY INVISIBLE (-2275 3050);
FORCEADD OFFPAGE..4
(-2450 3425);
FORCEPROP 2 LAST $XR0 145 
J 0
(-2264 3425);
DISPLAY 0.638298 (-2264 3425);
PAINT MONO (-2264 3425);
FORCEPROP 2 LAST CDS_LIB mstr_standard
J 0
(-2450 3425);
PAINT ORANGE (-2450 3425);
DISPLAY INVISIBLE (-2450 3425);
FORCEPROP 1 LAST OFFPAGE TRUE
J 0
(-2125 3300);
DISPLAY 1.170213 (-2125 3300);
PAINT GREEN (-2125 3300);
DISPLAY INVISIBLE (-2125 3300);
FORCEPROP 1 LAST COMMENT_BODY TRUE
J 0
(-2475 3325);
DISPLAY 1.170213 (-2475 3325);
PAINT GREEN (-2475 3325);
DISPLAY INVISIBLE (-2475 3325);
FORCEPROP 2 LAST PATH I145
J 0
(-2275 3500);
DISPLAY 1.021277 (-2275 3500);
PAINT ORANGE (-2275 3500);
DISPLAY INVISIBLE (-2275 3500);
FORCEADD OFFPAGE..2
(-2450 3725);
FORCEPROP 2 LAST $XR0 186 
J 0
(-2261 3725);
DISPLAY 0.638298 (-2261 3725);
PAINT MONO (-2261 3725);
FORCEPROP 2 LAST CDS_LIB mstr_standard
J 0
(-2450 3725);
PAINT ORANGE (-2450 3725);
DISPLAY INVISIBLE (-2450 3725);
FORCEPROP 1 LAST OFFPAGE TRUE
J 0
(-2125 3600);
DISPLAY 1.170213 (-2125 3600);
PAINT GREEN (-2125 3600);
DISPLAY INVISIBLE (-2125 3600);
FORCEPROP 1 LAST COMMENT_BODY TRUE
J 0
(-2495 3630);
DISPLAY 1.170213 (-2495 3630);
PAINT GREEN (-2495 3630);
DISPLAY INVISIBLE (-2495 3630);
FORCEPROP 2 LAST PATH I147
J 0
(-2275 3800);
DISPLAY 1.021277 (-2275 3800);
PAINT ORANGE (-2275 3800);
DISPLAY INVISIBLE (-2275 3800);
FORCEADD OFFPAGE..4
(-2450 3825);
FORCEPROP 2 LAST $XR1 222 
J 0
(-2144 3825);
DISPLAY 0.638298 (-2144 3825);
PAINT MONO (-2144 3825);
FORCEPROP 2 LAST $XR0 221 
J 0
(-2264 3825);
DISPLAY 0.638298 (-2264 3825);
PAINT MONO (-2264 3825);
FORCEPROP 2 LAST CDS_LIB mstr_standard
J 0
(-2450 3825);
PAINT ORANGE (-2450 3825);
DISPLAY INVISIBLE (-2450 3825);
FORCEPROP 1 LAST OFFPAGE TRUE
J 0
(-2125 3700);
DISPLAY 0.872340 (-2125 3700);
PAINT GREEN (-2125 3700);
DISPLAY INVISIBLE (-2125 3700);
FORCEPROP 1 LAST COMMENT_BODY TRUE
J 0
(-2475 3725);
DISPLAY 0.872340 (-2475 3725);
PAINT GREEN (-2475 3725);
DISPLAY INVISIBLE (-2475 3725);
FORCEPROP 2 LAST PATH I148
J 0
(-2275 3900);
DISPLAY 1.021277 (-2275 3900);
PAINT ORANGE (-2275 3900);
DISPLAY INVISIBLE (-2275 3900);
FORCEADD OFFPAGE..4
(-2450 3875);
FORCEPROP 2 LAST $XR1 133 
J 0
(-2144 3875);
DISPLAY 0.638298 (-2144 3875);
PAINT MONO (-2144 3875);
FORCEPROP 2 LAST $XR0 121 
J 0
(-2264 3875);
DISPLAY 0.638298 (-2264 3875);
PAINT MONO (-2264 3875);
FORCEPROP 2 LAST CDS_LIB mstr_standard
J 0
(-2450 3875);
PAINT ORANGE (-2450 3875);
DISPLAY INVISIBLE (-2450 3875);
FORCEPROP 1 LAST OFFPAGE TRUE
J 0
(-2125 3750);
DISPLAY 1.170213 (-2125 3750);
PAINT GREEN (-2125 3750);
DISPLAY INVISIBLE (-2125 3750);
FORCEPROP 1 LAST COMMENT_BODY TRUE
J 0
(-2475 3775);
DISPLAY 1.170213 (-2475 3775);
PAINT GREEN (-2475 3775);
DISPLAY INVISIBLE (-2475 3775);
FORCEPROP 2 LAST PATH I149
J 0
(-2275 3950);
DISPLAY 1.021277 (-2275 3950);
PAINT ORANGE (-2275 3950);
DISPLAY INVISIBLE (-2275 3950);
FORCEADD OFFPAGE..2
(-2450 2625);
FORCEPROP 2 LAST $XR0 181 
J 0
(-2261 2625);
DISPLAY 0.638298 (-2261 2625);
PAINT MONO (-2261 2625);
FORCEPROP 2 LAST CDS_LIB mstr_standard
J 0
(-2450 2625);
PAINT ORANGE (-2450 2625);
DISPLAY INVISIBLE (-2450 2625);
FORCEPROP 1 LAST OFFPAGE TRUE
J 0
(-2125 2500);
DISPLAY 1.170213 (-2125 2500);
PAINT GREEN (-2125 2500);
DISPLAY INVISIBLE (-2125 2500);
FORCEPROP 1 LAST COMMENT_BODY TRUE
J 0
(-2495 2530);
DISPLAY 1.170213 (-2495 2530);
PAINT GREEN (-2495 2530);
DISPLAY INVISIBLE (-2495 2530);
FORCEPROP 2 LAST PATH I151
J 0
(-2275 2700);
DISPLAY 1.021277 (-2275 2700);
PAINT ORANGE (-2275 2700);
DISPLAY INVISIBLE (-2275 2700);
FORCEADD OFFPAGE..2
R 2
(-6425 4225);
FORCEPROP 2 LAST $XR0 102 
J 0
(-6680 4225);
DISPLAY 0.638298 (-6680 4225);
PAINT MONO (-6680 4225);
FORCEPROP 2 LAST CDS_LIB mstr_standard
J 0
(-6425 4225);
PAINT MONO (-6425 4225);
DISPLAY INVISIBLE (-6425 4225);
FORCEPROP 1 LAST OFFPAGE TRUE
J 2
(-6750 4100);
DISPLAY 1.170213 (-6750 4100);
PAINT GREEN (-6750 4100);
DISPLAY INVISIBLE (-6750 4100);
FORCEPROP 1 LAST COMMENT_BODY TRUE
J 2
(-6380 4130);
DISPLAY 1.170213 (-6380 4130);
PAINT GREEN (-6380 4130);
DISPLAY INVISIBLE (-6380 4130);
FORCEPROP 2 LAST PATH I156
J 0
(-6375 4300);
DISPLAY 1.021277 (-6375 4300);
PAINT ORANGE (-6375 4300);
DISPLAY INVISIBLE (-6375 4300);
FORCEADD OFFPAGE..4
(-2450 2425);
FORCEPROP 2 LAST $XR0 192 
J 0
(-2264 2425);
DISPLAY 0.638298 (-2264 2425);
PAINT MONO (-2264 2425);
FORCEPROP 2 LAST CDS_LIB mstr_standard
J 0
(-2450 2425);
PAINT MONO (-2450 2425);
DISPLAY INVISIBLE (-2450 2425);
FORCEPROP 1 LAST OFFPAGE TRUE
J 0
(-2125 2300);
DISPLAY 1.170213 (-2125 2300);
PAINT GREEN (-2125 2300);
DISPLAY INVISIBLE (-2125 2300);
FORCEPROP 1 LAST COMMENT_BODY TRUE
J 0
(-2475 2325);
DISPLAY 1.170213 (-2475 2325);
PAINT GREEN (-2475 2325);
DISPLAY INVISIBLE (-2475 2325);
FORCEPROP 2 LAST PATH I157
J 0
(-2275 2500);
DISPLAY 1.021277 (-2275 2500);
PAINT ORANGE (-2275 2500);
DISPLAY INVISIBLE (-2275 2500);
FORCEADD OFFPAGE..2
(-2450 4125);
FORCEPROP 2 LAST $XR0 198 
J 0
(-2261 4125);
DISPLAY 0.638298 (-2261 4125);
PAINT MONO (-2261 4125);
FORCEPROP 2 LAST CDS_LIB mstr_standard
J 0
(-2450 4125);
PAINT MONO (-2450 4125);
DISPLAY INVISIBLE (-2450 4125);
FORCEPROP 1 LAST OFFPAGE TRUE
J 0
(-2125 4000);
DISPLAY 1.170213 (-2125 4000);
PAINT GREEN (-2125 4000);
DISPLAY INVISIBLE (-2125 4000);
FORCEPROP 1 LAST COMMENT_BODY TRUE
J 0
(-2495 4030);
DISPLAY 1.170213 (-2495 4030);
PAINT GREEN (-2495 4030);
DISPLAY INVISIBLE (-2495 4030);
FORCEPROP 2 LAST PATH I158
J 0
(-2275 4200);
DISPLAY 1.021277 (-2275 4200);
PAINT ORANGE (-2275 4200);
DISPLAY INVISIBLE (-2275 4200);
FORCEADD OFFPAGE..2
R 2
(-6425 2225);
FORCEPROP 2 LAST $XR0 218 
J 0
(-6680 2225);
DISPLAY 0.638298 (-6680 2225);
PAINT MONO (-6680 2225);
FORCEPROP 2 LAST CDS_LIB mstr_standard
J 0
(-6425 2225);
PAINT MONO (-6425 2225);
DISPLAY INVISIBLE (-6425 2225);
FORCEPROP 1 LAST OFFPAGE TRUE
J 2
(-6750 2100);
DISPLAY 0.872340 (-6750 2100);
PAINT GREEN (-6750 2100);
DISPLAY INVISIBLE (-6750 2100);
FORCEPROP 1 LAST COMMENT_BODY TRUE
J 2
(-6380 2130);
DISPLAY 0.872340 (-6380 2130);
PAINT GREEN (-6380 2130);
DISPLAY INVISIBLE (-6380 2130);
FORCEPROP 2 LAST PATH I160
J 0
(-6375 2300);
DISPLAY 1.021277 (-6375 2300);
PAINT ORANGE (-6375 2300);
DISPLAY INVISIBLE (-6375 2300);
FORCEADD OFFPAGE..2
R 2
(-6425 2975);
FORCEPROP 2 LAST $XR0 226 
J 0
(-6680 2975);
DISPLAY 0.638298 (-6680 2975);
PAINT MONO (-6680 2975);
FORCEPROP 2 LAST CDS_LIB mstr_standard
J 0
(-6425 2975);
PAINT MONO (-6425 2975);
DISPLAY INVISIBLE (-6425 2975);
FORCEPROP 1 LAST OFFPAGE TRUE
J 2
(-6750 2850);
DISPLAY 1.170213 (-6750 2850);
PAINT GREEN (-6750 2850);
DISPLAY INVISIBLE (-6750 2850);
FORCEPROP 1 LAST COMMENT_BODY TRUE
J 2
(-6380 2880);
DISPLAY 1.170213 (-6380 2880);
PAINT GREEN (-6380 2880);
DISPLAY INVISIBLE (-6380 2880);
FORCEPROP 2 LAST PATH I161
J 0
(-6375 3050);
DISPLAY 1.021277 (-6375 3050);
PAINT ORANGE (-6375 3050);
DISPLAY INVISIBLE (-6375 3050);
FORCEADD OFFPAGE..2
R 2
(-6425 2275);
FORCEPROP 2 LAST $XR0 215 
J 0
(-6680 2275);
DISPLAY 0.638298 (-6680 2275);
PAINT MONO (-6680 2275);
FORCEPROP 2 LAST CDS_LIB mstr_standard
J 0
(-6425 2275);
PAINT MONO (-6425 2275);
DISPLAY INVISIBLE (-6425 2275);
FORCEPROP 1 LAST OFFPAGE TRUE
J 2
(-6750 2150);
DISPLAY 1.170213 (-6750 2150);
PAINT GREEN (-6750 2150);
DISPLAY INVISIBLE (-6750 2150);
FORCEPROP 1 LAST COMMENT_BODY TRUE
J 2
(-6380 2180);
DISPLAY 1.170213 (-6380 2180);
PAINT GREEN (-6380 2180);
DISPLAY INVISIBLE (-6380 2180);
FORCEPROP 2 LAST PATH I162
J 0
(-6375 2350);
DISPLAY 1.021277 (-6375 2350);
PAINT ORANGE (-6375 2350);
DISPLAY INVISIBLE (-6375 2350);
FORCEADD OFFPAGE..1
(-6425 3025);
FORCEPROP 2 LAST $XR0 170 
J 0
(-6677 3025);
DISPLAY 0.638298 (-6677 3025);
PAINT MONO (-6677 3025);
FORCEPROP 2 LAST CDS_LIB mstr_standard
J 0
(-6425 3025);
PAINT MONO (-6425 3025);
DISPLAY INVISIBLE (-6425 3025);
FORCEPROP 1 LAST OFFPAGE TRUE
J 0
(-6100 2900);
DISPLAY 0.872340 (-6100 2900);
PAINT GREEN (-6100 2900);
DISPLAY INVISIBLE (-6100 2900);
FORCEPROP 1 LAST COMMENT_BODY TRUE
J 0
(-6300 2925);
DISPLAY 0.872340 (-6300 2925);
PAINT GREEN (-6300 2925);
DISPLAY INVISIBLE (-6300 2925);
FORCEPROP 2 LAST PATH I163
J 0
(-6375 3100);
DISPLAY 1.021277 (-6375 3100);
PAINT ORANGE (-6375 3100);
DISPLAY INVISIBLE (-6375 3100);
FORCEADD OFFPAGE..5
(-6425 2875);
FORCEPROP 2 LAST $XR0 170 
J 0
(-6680 2875);
DISPLAY 0.638298 (-6680 2875);
PAINT MONO (-6680 2875);
FORCEPROP 2 LAST CDS_LIB mstr_standard
J 0
(-6425 2875);
PAINT MONO (-6425 2875);
DISPLAY INVISIBLE (-6425 2875);
FORCEPROP 1 LAST OFFPAGE TRUE
J 0
(-6100 2750);
DISPLAY 0.872340 (-6100 2750);
PAINT GREEN (-6100 2750);
DISPLAY INVISIBLE (-6100 2750);
FORCEPROP 1 LAST COMMENT_BODY TRUE
J 0
(-6325 2800);
DISPLAY 0.872340 (-6325 2800);
PAINT GREEN (-6325 2800);
DISPLAY INVISIBLE (-6325 2800);
FORCEPROP 2 LAST PATH I164
J 0
(-6375 2950);
DISPLAY 1.021277 (-6375 2950);
PAINT ORANGE (-6375 2950);
DISPLAY INVISIBLE (-6375 2950);
FORCEADD OFFPAGE..4
R 2
(-6425 3175);
FORCEPROP 2 LAST $XR1 133 
J 0
(-6797 3175);
DISPLAY 0.638298 (-6797 3175);
PAINT MONO (-6797 3175);
FORCEPROP 2 LAST $XR0 121 
J 0
(-6677 3175);
DISPLAY 0.638298 (-6677 3175);
PAINT MONO (-6677 3175);
FORCEPROP 2 LAST CDS_LIB mstr_standard
J 0
(-6425 3175);
PAINT MONO (-6425 3175);
DISPLAY INVISIBLE (-6425 3175);
FORCEPROP 1 LAST OFFPAGE TRUE
J 2
(-6750 3050);
DISPLAY 1.170213 (-6750 3050);
PAINT GREEN (-6750 3050);
DISPLAY INVISIBLE (-6750 3050);
FORCEPROP 1 LAST COMMENT_BODY TRUE
J 2
(-6400 3075);
DISPLAY 1.170213 (-6400 3075);
PAINT GREEN (-6400 3075);
DISPLAY INVISIBLE (-6400 3075);
FORCEPROP 2 LAST PATH I165
J 0
(-6375 3250);
DISPLAY 1.021277 (-6375 3250);
PAINT ORANGE (-6375 3250);
DISPLAY INVISIBLE (-6375 3250);
FORCEADD RES..1
(-1425 2675);
FORCEPROP 1 LAST WATTAGE 1/16W
J 2
(-1125 2625);
DISPLAY 0.617021 (-1125 2625);
PAINT SKYBLUE (-1125 2625);
FORCEPROP 1 LAST TOLERANCE 5.0%
J 0
(-1375 2625);
DISPLAY 0.617021 (-1375 2625);
PAINT SKYBLUE (-1375 2625);
FORCEPROP 1 LAST LOCATION R2R6
J 0
(-1600 2700);
DISPLAY 0.617021 (-1600 2700);
PAINT AQUA (-1600 2700);
FORCEPROP 1 LAST PART_NUMBER G21497-048
J 0
(-1100 2625);
DISPLAY 0.617021 (-1100 2625);
PAINT BLUE (-1100 2625);
FORCEPROP 1 LASTPIN (-1525 2675) $PN 1
J 0
(-1513 2687);
DISPLAY 0.787234 (-1513 2687);
PAINT ORANGE (-1513 2687);
FORCEPROP 1 LAST VALUE 51
J 2
(-1450 2625);
DISPLAY 0.617021 (-1450 2625);
PAINT SKYBLUE (-1450 2625);
FORCEPROP 1 LASTPIN (-1325 2675) $PN 2
J 0
(-1363 2687);
DISPLAY 0.787234 (-1363 2687);
PAINT ORANGE (-1363 2687);
FORCEPROP 1 LAST PACK_TYPE 0402
J 0
(-1275 2575);
DISPLAY 0.617021 (-1275 2575);
PAINT SKYBLUE (-1275 2575);
FORCEPROP 1 LAST MATERIAL CHIP
J 0
(-1450 2575);
DISPLAY 0.617021 (-1450 2575);
PAINT SKYBLUE (-1450 2575);
FORCEPROP 2 LAST ROOM CPLD
J 0
(-1100 2675);
PAINT MONO (-1100 2675);
DISPLAY INVISIBLE (-1100 2675);
FORCEPROP 1 LAST PATH I166
J 0
(-1475 2825);
DISPLAY 0.978723 (-1475 2825);
PAINT WHITE (-1475 2825);
DISPLAY INVISIBLE (-1475 2825);
FORCEPROP 2 LAST CDS_LOCATION R2R6
J 0
(-1600 2700);
DISPLAY 0.617021 (-1600 2700);
PAINT AQUA (-1600 2700);
DISPLAY INVISIBLE (-1600 2700);
FORCEPROP 2 LAST CDS_LIB mstr_discrete
J 0
(-1425 2675);
PAINT MONO (-1425 2675);
DISPLAY INVISIBLE (-1425 2675);
FORCEPROP 2 LAST SEC 1
J 0
(-1475 2875);
PAINT MONO (-1475 2875);
DISPLAY INVISIBLE (-1475 2875);
FORCEPROP 2 LAST SEC_TYPE 0402
J 0
(-1475 2875);
DISPLAY 1.021277 (-1475 2875);
PAINT ORANGE (-1475 2875);
DISPLAY INVISIBLE (-1475 2875);
FORCEADD OFFPAGE..2
(-850 2675);
FORCEPROP 2 LASTPIN (-900 2675) SIG_NAME SGPIO_BMC_DIN
J 2
(-910 2685);
DISPLAY 0.617021 (-910 2685);
PAINT ORANGE (-910 2685);
FORCEPROP 2 LAST $XR0 144 
J 0
(-661 2675);
DISPLAY 0.638298 (-661 2675);
PAINT MONO (-661 2675);
FORCEPROP 2 LAST CDS_LIB mstr_standard
J 0
(-850 2675);
PAINT MONO (-850 2675);
DISPLAY INVISIBLE (-850 2675);
FORCEPROP 1 LAST OFFPAGE TRUE
J 0
(-525 2550);
DISPLAY 1.170213 (-525 2550);
PAINT GREEN (-525 2550);
DISPLAY INVISIBLE (-525 2550);
FORCEPROP 1 LAST COMMENT_BODY TRUE
J 0
(-895 2580);
DISPLAY 1.170213 (-895 2580);
PAINT GREEN (-895 2580);
DISPLAY INVISIBLE (-895 2580);
FORCEPROP 2 LAST PATH I167
J 0
(-675 2750);
DISPLAY 1.021277 (-675 2750);
PAINT ORANGE (-675 2750);
DISPLAY INVISIBLE (-675 2750);
FORCEADD OFFPAGE..4
R 2
(-6425 3275);
FORCEPROP 2 LAST $XR0 200 
J 0
(-6677 3275);
DISPLAY 0.638298 (-6677 3275);
PAINT MONO (-6677 3275);
FORCEPROP 2 LAST CDS_LIB mstr_standard
J 0
(-6425 3275);
PAINT MONO (-6425 3275);
DISPLAY INVISIBLE (-6425 3275);
FORCEPROP 1 LAST OFFPAGE TRUE
J 2
(-6750 3150);
DISPLAY 1.170213 (-6750 3150);
PAINT GREEN (-6750 3150);
DISPLAY INVISIBLE (-6750 3150);
FORCEPROP 1 LAST COMMENT_BODY TRUE
J 2
(-6400 3175);
DISPLAY 1.170213 (-6400 3175);
PAINT GREEN (-6400 3175);
DISPLAY INVISIBLE (-6400 3175);
FORCEPROP 2 LAST PATH I168
J 0
(-6375 3350);
DISPLAY 1.021277 (-6375 3350);
PAINT ORANGE (-6375 3350);
DISPLAY INVISIBLE (-6375 3350);
FORCEADD OFFPAGE..4
R 2
(-6425 3125);
FORCEPROP 2 LAST $XR2 144 
J 0
(-6917 3125);
DISPLAY 0.638298 (-6917 3125);
PAINT MONO (-6917 3125);
FORCEPROP 2 LAST $XR1 125 
J 0
(-6797 3125);
DISPLAY 0.638298 (-6797 3125);
PAINT MONO (-6797 3125);
FORCEPROP 2 LAST $XR0 119 
J 0
(-6677 3125);
DISPLAY 0.638298 (-6677 3125);
PAINT MONO (-6677 3125);
FORCEPROP 2 LAST CDS_LIB mstr_standard
J 0
(-6425 3125);
PAINT MONO (-6425 3125);
DISPLAY INVISIBLE (-6425 3125);
FORCEPROP 1 LAST OFFPAGE TRUE
J 2
(-6750 3000);
DISPLAY 1.170213 (-6750 3000);
PAINT GREEN (-6750 3000);
DISPLAY INVISIBLE (-6750 3000);
FORCEPROP 1 LAST COMMENT_BODY TRUE
J 2
(-6400 3025);
DISPLAY 1.170213 (-6400 3025);
PAINT GREEN (-6400 3025);
DISPLAY INVISIBLE (-6400 3025);
FORCEPROP 2 LAST PATH I169
J 0
(-6375 3200);
DISPLAY 1.021277 (-6375 3200);
PAINT ORANGE (-6375 3200);
DISPLAY INVISIBLE (-6375 3200);
FORCEADD OFFPAGE..4
(-2450 3675);
FORCEPROP 2 LAST $XR0 238 
J 0
(-2264 3675);
DISPLAY 0.638298 (-2264 3675);
PAINT MONO (-2264 3675);
FORCEPROP 2 LAST CDS_LIB mstr_standard
J 0
(-2450 3675);
PAINT ORANGE (-2450 3675);
DISPLAY INVISIBLE (-2450 3675);
FORCEPROP 1 LAST OFFPAGE TRUE
J 0
(-2125 3550);
DISPLAY 1.170213 (-2125 3550);
PAINT GREEN (-2125 3550);
DISPLAY INVISIBLE (-2125 3550);
FORCEPROP 1 LAST COMMENT_BODY TRUE
J 0
(-2475 3575);
DISPLAY 1.170213 (-2475 3575);
PAINT GREEN (-2475 3575);
DISPLAY INVISIBLE (-2475 3575);
FORCEPROP 2 LAST PATH I17
J 0
(-1800 3725);
DISPLAY 1.021277 (-1800 3725);
PAINT ORANGE (-1800 3725);
DISPLAY INVISIBLE (-1800 3725);
FORCEADD OFFPAGE..4
(-850 3325);
FORCEPROP 2 LAST $XR1 144 
J 0
(-544 3325);
DISPLAY 0.638298 (-544 3325);
PAINT MONO (-544 3325);
FORCEPROP 2 LAST $XR0 120 
J 0
(-664 3325);
DISPLAY 0.638298 (-664 3325);
PAINT MONO (-664 3325);
FORCEPROP 2 LAST CDS_LIB mstr_standard
J 0
(-850 3325);
PAINT MONO (-850 3325);
DISPLAY INVISIBLE (-850 3325);
FORCEPROP 1 LAST OFFPAGE TRUE
J 0
(-525 3200);
DISPLAY 1.170213 (-525 3200);
PAINT GREEN (-525 3200);
DISPLAY INVISIBLE (-525 3200);
FORCEPROP 1 LAST COMMENT_BODY TRUE
J 0
(-875 3225);
DISPLAY 1.170213 (-875 3225);
PAINT GREEN (-875 3225);
DISPLAY INVISIBLE (-875 3225);
FORCEPROP 2 LAST PATH I170
J 0
(-675 3400);
DISPLAY 1.021277 (-675 3400);
PAINT ORANGE (-675 3400);
DISPLAY INVISIBLE (-675 3400);
FORCEADD P3V3_STBY..1
(-1375 3750);
FORCEPROP 3 LASTPIN (-1375 3700) SIG_NAME P3V3_STBY\g
J 0
(-1365 3710);
DISPLAY 0.659574 (-1365 3710);
PAINT MONO (-1365 3710);
DISPLAY INVISIBLE (-1365 3710);
FORCEPROP 1 LAST VOLTAGE 3.3V
J 0
(-1420 3707);
DISPLAY 0.340426 (-1420 3707);
PAINT SKYBLUE (-1420 3707);
DISPLAY INVISIBLE (-1420 3707);
FORCEPROP 1 LAST HDL_POWER P3V3_STBY
J 0
(-1675 3625);
DISPLAY 0.872340 (-1675 3625);
PAINT ORANGE (-1675 3625);
DISPLAY INVISIBLE (-1675 3625);
FORCEPROP 1 LAST PATH I171
J 0
(-1330 3752);
DISPLAY 0.340426 (-1330 3752);
PAINT GREEN (-1330 3752);
DISPLAY INVISIBLE (-1330 3752);
FORCEPROP 1 LAST BODY_TYPE PLUMBING
J 0
(-1420 3707);
DISPLAY 0.340426 (-1420 3707);
PAINT GREEN (-1420 3707);
DISPLAY INVISIBLE (-1420 3707);
FORCEPROP 2 LAST CDS_LIB mstr_symbols
J 0
(-1375 3750);
PAINT MONO (-1375 3750);
DISPLAY INVISIBLE (-1375 3750);
FORCEPROP 1 LAST SIZE 1B
J 0
(-1330 3772);
DISPLAY 0.340426 (-1330 3772);
PAINT GREEN (-1330 3772);
DISPLAY INVISIBLE (-1330 3772);
FORCEADD RES..2
R 2
(-1375 3550);
FORCEPROP 1 LAST LOCATION R2R7
J 2
(-1420 3675);
DISPLAY 0.617021 (-1420 3675);
PAINT AQUA (-1420 3675);
FORCEPROP 1 LAST PART_NUMBER G21796-072
J 2
(-1415 3425);
DISPLAY 0.617021 (-1415 3425);
PAINT BLUE (-1415 3425);
FORCEPROP 1 LAST MATERIAL CHIP
J 2
(-1415 3475);
DISPLAY 0.617021 (-1415 3475);
PAINT SKYBLUE (-1415 3475);
FORCEPROP 1 LAST PACK_TYPE 0402
J 2
(-1415 3375);
DISPLAY 0.617021 (-1415 3375);
PAINT SKYBLUE (-1415 3375);
FORCEPROP 1 LASTPIN (-1375 3450) $PN 2
J 2
(-1380 3460);
DISPLAY 0.787234 (-1380 3460);
PAINT ORANGE (-1380 3460);
FORCEPROP 1 LAST WATTAGE 1/16W
J 2
(-1415 3525);
DISPLAY 0.617021 (-1415 3525);
PAINT SKYBLUE (-1415 3525);
FORCEPROP 1 LAST TOLERANCE 1%
J 2
(-1420 3575);
DISPLAY 0.617021 (-1420 3575);
PAINT SKYBLUE (-1420 3575);
FORCEPROP 1 LAST VALUE 4.75K
J 2
(-1420 3625);
DISPLAY 0.617021 (-1420 3625);
PAINT SKYBLUE (-1420 3625);
FORCEPROP 1 LASTPIN (-1375 3650) $PN 1
J 2
(-1380 3612);
DISPLAY 0.787234 (-1380 3612);
PAINT ORANGE (-1380 3612);
FORCEPROP 2 LAST ROOM CPLD
J 0
(-1400 3650);
PAINT MONO (-1400 3650);
DISPLAY INVISIBLE (-1400 3650);
FORCEPROP 1 LAST PATH I172
J 2
(-1425 3725);
DISPLAY 0.978723 (-1425 3725);
PAINT WHITE (-1425 3725);
DISPLAY INVISIBLE (-1425 3725);
FORCEPROP 2 LAST CDS_LOCATION R2R7
J 2
(-1420 3675);
DISPLAY 0.617021 (-1420 3675);
PAINT AQUA (-1420 3675);
DISPLAY INVISIBLE (-1420 3675);
FORCEPROP 2 LAST BOM_COST CPLD
J 0
(-1400 3700);
PAINT MONO (-1400 3700);
DISPLAY INVISIBLE (-1400 3700);
FORCEPROP 2 LAST SIGNAL_MODEL DEFAULT_RESISTOR_47000OHM_2_1
J 0
(-1425 3775);
PAINT MONO (-1425 3775);
DISPLAY INVISIBLE (-1425 3775);
FORCEPROP 2 LAST CDS_LIB mstr_discrete
J 0
(-1375 3550);
PAINT MONO (-1375 3550);
DISPLAY INVISIBLE (-1375 3550);
FORCEPROP 2 LAST SEC 1
J 0
(-1425 3775);
PAINT MONO (-1425 3775);
DISPLAY INVISIBLE (-1425 3775);
FORCEPROP 2 LAST SEC_TYPE 0402
J 0
(-1425 3775);
DISPLAY 1.021277 (-1425 3775);
PAINT ORANGE (-1425 3775);
DISPLAY INVISIBLE (-1425 3775);
FORCEADD OFFPAGE..2
(-2450 4075);
FORCEPROP 2 LAST $XR1 145 
J 0
(-2141 4075);
DISPLAY 0.638298 (-2141 4075);
PAINT MONO (-2141 4075);
FORCEPROP 2 LAST $XR0 120 
J 0
(-2261 4075);
DISPLAY 0.638298 (-2261 4075);
PAINT MONO (-2261 4075);
FORCEPROP 2 LAST CDS_LIB mstr_standard
J 0
(-2450 4075);
PAINT MONO (-2450 4075);
DISPLAY INVISIBLE (-2450 4075);
FORCEPROP 1 LAST OFFPAGE TRUE
J 0
(-2125 3950);
DISPLAY 1.170213 (-2125 3950);
PAINT GREEN (-2125 3950);
DISPLAY INVISIBLE (-2125 3950);
FORCEPROP 1 LAST COMMENT_BODY TRUE
J 0
(-2495 3980);
DISPLAY 1.170213 (-2495 3980);
PAINT GREEN (-2495 3980);
DISPLAY INVISIBLE (-2495 3980);
FORCEPROP 2 LAST PATH I173
J 0
(-2275 4150);
DISPLAY 1.021277 (-2275 4150);
PAINT ORANGE (-2275 4150);
DISPLAY INVISIBLE (-2275 4150);
FORCEADD OFFPAGE..2
R 2
(-6425 3625);
FORCEPROP 2 LAST $XR1 119 
J 0
(-6800 3625);
DISPLAY 0.638298 (-6800 3625);
PAINT MONO (-6800 3625);
FORCEPROP 2 LAST $XR0 145 
J 0
(-6680 3625);
DISPLAY 0.638298 (-6680 3625);
PAINT MONO (-6680 3625);
FORCEPROP 2 LAST CDS_LIB mstr_standard
J 0
(-6425 3625);
PAINT MONO (-6425 3625);
DISPLAY INVISIBLE (-6425 3625);
FORCEPROP 1 LAST OFFPAGE TRUE
J 2
(-6750 3500);
DISPLAY 1.170213 (-6750 3500);
PAINT GREEN (-6750 3500);
DISPLAY INVISIBLE (-6750 3500);
FORCEPROP 1 LAST COMMENT_BODY TRUE
J 2
(-6380 3530);
DISPLAY 1.170213 (-6380 3530);
PAINT GREEN (-6380 3530);
DISPLAY INVISIBLE (-6380 3530);
FORCEPROP 2 LAST PATH I174
J 0
(-6375 3700);
DISPLAY 1.021277 (-6375 3700);
PAINT ORANGE (-6375 3700);
DISPLAY INVISIBLE (-6375 3700);
FORCEADD OFFPAGE..2
R 2
(-6425 1875);
FORCEPROP 2 LAST $XR1 145 
J 0
(-6800 1875);
DISPLAY 0.638298 (-6800 1875);
PAINT MONO (-6800 1875);
FORCEPROP 2 LAST $XR0 120 
J 0
(-6680 1875);
DISPLAY 0.638298 (-6680 1875);
PAINT MONO (-6680 1875);
FORCEPROP 2 LAST CDS_LIB mstr_standard
J 0
(-6425 1875);
PAINT ORANGE (-6425 1875);
DISPLAY INVISIBLE (-6425 1875);
FORCEPROP 1 LAST OFFPAGE TRUE
J 2
(-6750 1750);
DISPLAY 1.170213 (-6750 1750);
PAINT GREEN (-6750 1750);
DISPLAY INVISIBLE (-6750 1750);
FORCEPROP 1 LAST COMMENT_BODY TRUE
J 2
(-6380 1780);
DISPLAY 1.170213 (-6380 1780);
PAINT GREEN (-6380 1780);
DISPLAY INVISIBLE (-6380 1780);
FORCEPROP 2 LAST PATH I175
J 0
(-6375 1950);
DISPLAY 1.021277 (-6375 1950);
PAINT ORANGE (-6375 1950);
DISPLAY INVISIBLE (-6375 1950);
FORCEADD OFFPAGE..2
(-2450 2375);
FORCEPROP 2 LAST $XR0 201 
J 0
(-2261 2375);
DISPLAY 0.638298 (-2261 2375);
PAINT MONO (-2261 2375);
FORCEPROP 2 LAST CDS_LIB mstr_standard
J 0
(-2450 2375);
PAINT ORANGE (-2450 2375);
DISPLAY INVISIBLE (-2450 2375);
FORCEPROP 1 LAST OFFPAGE TRUE
J 0
(-2125 2250);
DISPLAY 1.170213 (-2125 2250);
PAINT GREEN (-2125 2250);
DISPLAY INVISIBLE (-2125 2250);
FORCEPROP 1 LAST COMMENT_BODY TRUE
J 0
(-2495 2280);
DISPLAY 1.170213 (-2495 2280);
PAINT GREEN (-2495 2280);
DISPLAY INVISIBLE (-2495 2280);
FORCEPROP 2 LAST PATH I176
J 0
(-2275 2450);
DISPLAY 1.021277 (-2275 2450);
PAINT ORANGE (-2275 2450);
DISPLAY INVISIBLE (-2275 2450);
FORCEADD OFFPAGE..2
R 2
(-6425 2925);
FORCEPROP 2 LAST $XR0 223 
J 0
(-6680 2925);
DISPLAY 0.638298 (-6680 2925);
PAINT MONO (-6680 2925);
FORCEPROP 2 LAST CDS_LIB mstr_standard
J 0
(-6425 2925);
PAINT ORANGE (-6425 2925);
DISPLAY INVISIBLE (-6425 2925);
FORCEPROP 1 LAST OFFPAGE TRUE
J 2
(-6750 2800);
DISPLAY 1.170213 (-6750 2800);
PAINT GREEN (-6750 2800);
DISPLAY INVISIBLE (-6750 2800);
FORCEPROP 1 LAST COMMENT_BODY TRUE
J 2
(-6380 2830);
DISPLAY 1.170213 (-6380 2830);
PAINT GREEN (-6380 2830);
DISPLAY INVISIBLE (-6380 2830);
FORCEPROP 2 LAST PATH I177
J 0
(-6375 3000);
DISPLAY 1.021277 (-6375 3000);
PAINT ORANGE (-6375 3000);
DISPLAY INVISIBLE (-6375 3000);
FORCEADD OFFPAGE..4
R 2
(-6425 2025);
FORCEPROP 2 LAST $XR0 213 
J 0
(-6677 2025);
DISPLAY 0.638298 (-6677 2025);
PAINT MONO (-6677 2025);
FORCEPROP 2 LAST CDS_LIB mstr_standard
J 0
(-6425 2025);
PAINT ORANGE (-6425 2025);
DISPLAY INVISIBLE (-6425 2025);
FORCEPROP 1 LAST OFFPAGE TRUE
J 2
(-6750 1900);
DISPLAY 1.170213 (-6750 1900);
PAINT GREEN (-6750 1900);
DISPLAY INVISIBLE (-6750 1900);
FORCEPROP 1 LAST COMMENT_BODY TRUE
J 2
(-6400 1925);
DISPLAY 1.170213 (-6400 1925);
PAINT GREEN (-6400 1925);
DISPLAY INVISIBLE (-6400 1925);
FORCEPROP 2 LAST PATH I178
J 0
(-6375 2100);
DISPLAY 1.021277 (-6375 2100);
PAINT ORANGE (-6375 2100);
DISPLAY INVISIBLE (-6375 2100);
FORCEADD OFFPAGE..2
R 2
(-6425 1275);
FORCEPROP 2 LAST $XR0 206 
J 0
(-6680 1275);
DISPLAY 0.638298 (-6680 1275);
PAINT MONO (-6680 1275);
FORCEPROP 2 LAST CDS_LIB mstr_standard
J 0
(-6425 1275);
PAINT ORANGE (-6425 1275);
DISPLAY INVISIBLE (-6425 1275);
FORCEPROP 1 LAST OFFPAGE TRUE
J 2
(-6750 1150);
DISPLAY 1.170213 (-6750 1150);
PAINT GREEN (-6750 1150);
DISPLAY INVISIBLE (-6750 1150);
FORCEPROP 1 LAST COMMENT_BODY TRUE
J 2
(-6380 1180);
DISPLAY 1.170213 (-6380 1180);
PAINT GREEN (-6380 1180);
DISPLAY INVISIBLE (-6380 1180);
FORCEPROP 2 LAST PATH I179
J 0
(-6375 1350);
DISPLAY 1.021277 (-6375 1350);
PAINT ORANGE (-6375 1350);
DISPLAY INVISIBLE (-6375 1350);
FORCEADD OFFPAGE..2
(-2450 3625);
FORCEPROP 2 LAST $XR0 245 
J 0
(-2261 3625);
DISPLAY 0.638298 (-2261 3625);
PAINT MONO (-2261 3625);
FORCEPROP 2 LAST CDS_LIB mstr_standard
J 2
(-2450 3625);
PAINT ORANGE (-2450 3625);
DISPLAY INVISIBLE (-2450 3625);
FORCEPROP 1 LAST OFFPAGE TRUE
J 0
(-2125 3500);
DISPLAY 1.170213 (-2125 3500);
PAINT GREEN (-2125 3500);
DISPLAY INVISIBLE (-2125 3500);
FORCEPROP 1 LAST COMMENT_BODY TRUE
J 0
(-2495 3530);
DISPLAY 1.170213 (-2495 3530);
PAINT GREEN (-2495 3530);
DISPLAY INVISIBLE (-2495 3530);
FORCEPROP 2 LAST PATH I18
J 0
(-2250 3675);
DISPLAY 1.021277 (-2250 3675);
PAINT ORANGE (-2250 3675);
DISPLAY INVISIBLE (-2250 3675);
FORCEADD OFFPAGE..4
R 2
(-6425 4075);
FORCEPROP 2 LAST $XR0 193 
J 0
(-6677 4075);
DISPLAY 0.638298 (-6677 4075);
PAINT MONO (-6677 4075);
FORCEPROP 2 LAST CDS_LIB mstr_standard
J 0
(-6425 4075);
PAINT ORANGE (-6425 4075);
DISPLAY INVISIBLE (-6425 4075);
FORCEPROP 1 LAST OFFPAGE TRUE
J 2
(-6750 3950);
DISPLAY 1.170213 (-6750 3950);
PAINT GREEN (-6750 3950);
DISPLAY INVISIBLE (-6750 3950);
FORCEPROP 1 LAST COMMENT_BODY TRUE
J 2
(-6400 3975);
DISPLAY 1.170213 (-6400 3975);
PAINT GREEN (-6400 3975);
DISPLAY INVISIBLE (-6400 3975);
FORCEPROP 2 LAST PATH I180
J 0
(-6375 4150);
DISPLAY 1.021277 (-6375 4150);
PAINT ORANGE (-6375 4150);
DISPLAY INVISIBLE (-6375 4150);
FORCEADD OFFPAGE..4
R 2
(-6425 3925);
FORCEPROP 2 LAST $XR0 194 
J 0
(-6707 3925);
DISPLAY 0.638298 (-6707 3925);
PAINT MONO (-6707 3925);
FORCEPROP 2 LAST CDS_LIB mstr_standard
J 0
(-6425 3925);
PAINT ORANGE (-6425 3925);
DISPLAY INVISIBLE (-6425 3925);
FORCEPROP 1 LAST OFFPAGE TRUE
J 2
(-6750 3800);
DISPLAY 1.170213 (-6750 3800);
PAINT GREEN (-6750 3800);
DISPLAY INVISIBLE (-6750 3800);
FORCEPROP 1 LAST COMMENT_BODY TRUE
J 2
(-6400 3825);
DISPLAY 1.170213 (-6400 3825);
PAINT GREEN (-6400 3825);
DISPLAY INVISIBLE (-6400 3825);
FORCEPROP 2 LAST PATH I181
J 0
(-6375 4000);
DISPLAY 1.021277 (-6375 4000);
PAINT ORANGE (-6375 4000);
DISPLAY INVISIBLE (-6375 4000);
FORCEADD OFFPAGE..2
R 2
(-6425 3775);
FORCEPROP 2 LAST $XR0 194 
J 0
(-6680 3775);
DISPLAY 0.638298 (-6680 3775);
PAINT MONO (-6680 3775);
FORCEPROP 2 LAST CDS_LIB mstr_standard
J 0
(-6425 3775);
PAINT ORANGE (-6425 3775);
DISPLAY INVISIBLE (-6425 3775);
FORCEPROP 1 LAST OFFPAGE TRUE
J 2
(-6750 3650);
DISPLAY 1.170213 (-6750 3650);
PAINT GREEN (-6750 3650);
DISPLAY INVISIBLE (-6750 3650);
FORCEPROP 1 LAST COMMENT_BODY TRUE
J 2
(-6380 3680);
DISPLAY 1.170213 (-6380 3680);
PAINT GREEN (-6380 3680);
DISPLAY INVISIBLE (-6380 3680);
FORCEPROP 2 LAST PATH I182
J 0
(-6375 3850);
DISPLAY 1.021277 (-6375 3850);
PAINT ORANGE (-6375 3850);
DISPLAY INVISIBLE (-6375 3850);
FORCEADD OFFPAGE..2
R 2
(-6425 3425);
FORCEPROP 2 LAST $XR0 193 
J 0
(-6680 3425);
DISPLAY 0.638298 (-6680 3425);
PAINT MONO (-6680 3425);
FORCEPROP 2 LAST CDS_LIB mstr_standard
J 0
(-6425 3425);
PAINT ORANGE (-6425 3425);
DISPLAY INVISIBLE (-6425 3425);
FORCEPROP 1 LAST OFFPAGE TRUE
J 2
(-6750 3300);
DISPLAY 1.170213 (-6750 3300);
PAINT GREEN (-6750 3300);
DISPLAY INVISIBLE (-6750 3300);
FORCEPROP 1 LAST COMMENT_BODY TRUE
J 2
(-6380 3330);
DISPLAY 1.170213 (-6380 3330);
PAINT GREEN (-6380 3330);
DISPLAY INVISIBLE (-6380 3330);
FORCEPROP 2 LAST PATH I183
J 0
(-6375 3500);
DISPLAY 1.021277 (-6375 3500);
PAINT ORANGE (-6375 3500);
DISPLAY INVISIBLE (-6375 3500);
FORCEADD RES..1
(-3175 4325);
FORCEPROP 1 LAST PACK_TYPE 0402
J 0
(-3475 4425);
DISPLAY 0.617021 (-3475 4425);
PAINT SKYBLUE (-3475 4425);
FORCEPROP 1 LASTPIN (-3275 4325) $PN 1
J 0
(-3263 4337);
DISPLAY 0.617021 (-3263 4337);
PAINT ORANGE (-3263 4337);
FORCEPROP 1 LAST VALUE 0.0
J 2
(-3275 4425);
DISPLAY 0.617021 (-3275 4425);
PAINT SKYBLUE (-3275 4425);
FORCEPROP 1 LAST LOCATION R2R4
J 0
(-3225 4375);
DISPLAY 0.617021 (-3225 4375);
PAINT AQUA (-3225 4375);
FORCEPROP 1 LASTPIN (-3075 4325) $PN 2
J 0
(-3113 4337);
DISPLAY 0.617021 (-3113 4337);
PAINT ORANGE (-3113 4337);
FORCEPROP 1 LAST PART_NUMBER G21497-005
J 0
(-3225 4425);
DISPLAY 0.617021 (-3225 4425);
PAINT BLUE (-3225 4425);
FORCEPROP 1 LAST MATERIAL CHIP
J 0
(-2975 4425);
DISPLAY 0.617021 (-2975 4425);
PAINT SKYBLUE (-2975 4425);
FORCEPROP 1 LAST TOLERANCE 5%
J 0
(-3050 4375);
DISPLAY 0.638298 (-3050 4375);
PAINT SKYBLUE (-3050 4375);
FORCEPROP 1 LAST WATTAGE 1/16W
J 0
(-2900 4375);
DISPLAY 0.638298 (-2900 4375);
PAINT SKYBLUE (-2900 4375);
FORCEPROP 0 LAST ROOM CPLD
J 0
(-2975 4525);
DISPLAY 1.021277 (-2975 4525);
PAINT ORANGE (-2975 4525);
DISPLAY INVISIBLE (-2975 4525);
FORCEPROP 1 LAST PATH I184
J 0
(-3225 4475);
DISPLAY 0.978723 (-3225 4475);
PAINT WHITE (-3225 4475);
DISPLAY INVISIBLE (-3225 4475);
FORCEPROP 2 LAST CDS_LOCATION R2R4
J 0
(-3225 4375);
DISPLAY 0.617021 (-3225 4375);
PAINT AQUA (-3225 4375);
DISPLAY INVISIBLE (-3225 4375);
FORCEPROP 2 LAST $SEC 1
J 0
(-3225 4525);
PAINT MONO (-3225 4525);
DISPLAY INVISIBLE (-3225 4525);
FORCEPROP 2 LAST CDS_SEC 1
J 0
(-3225 4525);
PAINT MONO (-3225 4525);
DISPLAY INVISIBLE (-3225 4525);
FORCEPROP 0 LAST BOM_COST CPLD
J 0
(-2975 4625);
DISPLAY 1.021277 (-2975 4625);
PAINT ORANGE (-2975 4625);
DISPLAY INVISIBLE (-2975 4625);
FORCEPROP 2 LAST CDS_LIB mstr_discrete
J 0
(-3175 4325);
PAINT ORANGE (-3175 4325);
DISPLAY INVISIBLE (-3175 4325);
FORCEADD OFFPAGE..4
(-2450 4275);
FORCEPROP 2 LASTPIN (-2500 4275) SIG_NAME PWRGD_P12V_MAIN
J 0
(-3085 4285);
DISPLAY 0.617021 (-3085 4285);
PAINT ORANGE (-3085 4285);
FORCEPROP 2 LAST $XR0 196 
J 0
(-2264 4275);
DISPLAY 0.638298 (-2264 4275);
PAINT MONO (-2264 4275);
FORCEPROP 2 LAST CDS_LIB mstr_standard
J 0
(-2450 4275);
PAINT ORANGE (-2450 4275);
DISPLAY INVISIBLE (-2450 4275);
FORCEPROP 1 LAST OFFPAGE TRUE
J 0
(-2125 4150);
DISPLAY 1.170213 (-2125 4150);
PAINT GREEN (-2125 4150);
DISPLAY INVISIBLE (-2125 4150);
FORCEPROP 1 LAST COMMENT_BODY TRUE
J 0
(-2475 4175);
DISPLAY 1.170213 (-2475 4175);
PAINT GREEN (-2475 4175);
DISPLAY INVISIBLE (-2475 4175);
FORCEPROP 2 LAST PATH I185
J 0
(-2275 4350);
DISPLAY 1.021277 (-2275 4350);
PAINT ORANGE (-2275 4350);
DISPLAY INVISIBLE (-2275 4350);
FORCEADD OFFPAGE..2
R 2
(-6425 3725);
FORCEPROP 2 LAST $XR0 102 
J 0
(-6680 3725);
DISPLAY 0.638298 (-6680 3725);
PAINT MONO (-6680 3725);
FORCEPROP 2 LAST CDS_LIB mstr_standard
J 0
(-6425 3725);
PAINT ORANGE (-6425 3725);
DISPLAY INVISIBLE (-6425 3725);
FORCEPROP 1 LAST OFFPAGE TRUE
J 2
(-6750 3600);
DISPLAY 1.170213 (-6750 3600);
PAINT GREEN (-6750 3600);
DISPLAY INVISIBLE (-6750 3600);
FORCEPROP 1 LAST COMMENT_BODY TRUE
J 2
(-6380 3630);
DISPLAY 1.170213 (-6380 3630);
PAINT GREEN (-6380 3630);
DISPLAY INVISIBLE (-6380 3630);
FORCEPROP 2 LAST PATH I186
J 0
(-6375 3800);
DISPLAY 1.021277 (-6375 3800);
PAINT ORANGE (-6375 3800);
DISPLAY INVISIBLE (-6375 3800);
FORCEADD OFFPAGE..2
R 2
(-6425 3475);
FORCEPROP 2 LAST $XR0 102 
J 0
(-6680 3475);
DISPLAY 0.638298 (-6680 3475);
PAINT MONO (-6680 3475);
FORCEPROP 2 LAST CDS_LIB mstr_standard
J 0
(-6425 3475);
PAINT ORANGE (-6425 3475);
DISPLAY INVISIBLE (-6425 3475);
FORCEPROP 1 LAST OFFPAGE TRUE
J 2
(-6750 3350);
DISPLAY 1.170213 (-6750 3350);
PAINT GREEN (-6750 3350);
DISPLAY INVISIBLE (-6750 3350);
FORCEPROP 1 LAST COMMENT_BODY TRUE
J 2
(-6380 3380);
DISPLAY 1.170213 (-6380 3380);
PAINT GREEN (-6380 3380);
DISPLAY INVISIBLE (-6380 3380);
FORCEPROP 2 LAST PATH I187
J 0
(-6375 3550);
DISPLAY 1.021277 (-6375 3550);
PAINT ORANGE (-6375 3550);
DISPLAY INVISIBLE (-6375 3550);
FORCEADD OFFPAGE..2
R 2
(-6425 1225);
FORCEPROP 2 LAST $XR0 104 
J 0
(-6680 1225);
DISPLAY 0.638298 (-6680 1225);
PAINT MONO (-6680 1225);
FORCEPROP 2 LAST CDS_LIB mstr_standard
J 0
(-6425 1225);
PAINT ORANGE (-6425 1225);
DISPLAY INVISIBLE (-6425 1225);
FORCEPROP 1 LAST OFFPAGE TRUE
J 2
(-6750 1100);
DISPLAY 1.170213 (-6750 1100);
PAINT GREEN (-6750 1100);
DISPLAY INVISIBLE (-6750 1100);
FORCEPROP 1 LAST COMMENT_BODY TRUE
J 2
(-6380 1130);
DISPLAY 1.170213 (-6380 1130);
PAINT GREEN (-6380 1130);
DISPLAY INVISIBLE (-6380 1130);
FORCEPROP 2 LAST PATH I188
J 0
(-6375 1300);
DISPLAY 1.021277 (-6375 1300);
PAINT ORANGE (-6375 1300);
DISPLAY INVISIBLE (-6375 1300);
FORCEADD OFFPAGE..2
(-2450 1925);
FORCEPROP 2 LAST $XR0 113 
J 0
(-2261 1925);
DISPLAY 0.638298 (-2261 1925);
PAINT MONO (-2261 1925);
FORCEPROP 2 LAST CDS_LIB mstr_standard
J 0
(-2450 1925);
PAINT ORANGE (-2450 1925);
DISPLAY INVISIBLE (-2450 1925);
FORCEPROP 1 LAST OFFPAGE TRUE
J 0
(-2125 1800);
DISPLAY 1.170213 (-2125 1800);
PAINT GREEN (-2125 1800);
DISPLAY INVISIBLE (-2125 1800);
FORCEPROP 1 LAST COMMENT_BODY TRUE
J 0
(-2495 1830);
DISPLAY 1.170213 (-2495 1830);
PAINT GREEN (-2495 1830);
DISPLAY INVISIBLE (-2495 1830);
FORCEPROP 2 LAST PATH I189
J 0
(-2275 2000);
DISPLAY 1.021277 (-2275 2000);
PAINT ORANGE (-2275 2000);
DISPLAY INVISIBLE (-2275 2000);
FORCEADD OFFPAGE..4
(-2450 3575);
FORCEPROP 2 LAST $XR0 189 
J 0
(-2264 3575);
DISPLAY 0.638298 (-2264 3575);
PAINT MONO (-2264 3575);
FORCEPROP 2 LAST CDS_LIB mstr_standard
J 0
(-2450 3575);
PAINT ORANGE (-2450 3575);
DISPLAY INVISIBLE (-2450 3575);
FORCEPROP 1 LAST OFFPAGE TRUE
J 0
(-2125 3450);
DISPLAY 1.170213 (-2125 3450);
PAINT GREEN (-2125 3450);
DISPLAY INVISIBLE (-2125 3450);
FORCEPROP 1 LAST COMMENT_BODY TRUE
J 0
(-2475 3475);
DISPLAY 1.170213 (-2475 3475);
PAINT GREEN (-2475 3475);
DISPLAY INVISIBLE (-2475 3475);
FORCEPROP 2 LAST PATH I19
J 0
(-2250 3625);
DISPLAY 1.021277 (-2250 3625);
PAINT ORANGE (-2250 3625);
DISPLAY INVISIBLE (-2250 3625);
FORCEADD OFFPAGE..2
(-2450 1875);
FORCEPROP 2 LAST $XR0 113 
J 0
(-2261 1875);
DISPLAY 0.638298 (-2261 1875);
PAINT MONO (-2261 1875);
FORCEPROP 2 LAST CDS_LIB mstr_standard
J 0
(-2450 1875);
PAINT ORANGE (-2450 1875);
DISPLAY INVISIBLE (-2450 1875);
FORCEPROP 1 LAST OFFPAGE TRUE
J 0
(-2125 1750);
DISPLAY 1.170213 (-2125 1750);
PAINT GREEN (-2125 1750);
DISPLAY INVISIBLE (-2125 1750);
FORCEPROP 1 LAST COMMENT_BODY TRUE
J 0
(-2495 1780);
DISPLAY 1.170213 (-2495 1780);
PAINT GREEN (-2495 1780);
DISPLAY INVISIBLE (-2495 1780);
FORCEPROP 2 LAST PATH I190
J 0
(-2275 1950);
DISPLAY 1.021277 (-2275 1950);
PAINT ORANGE (-2275 1950);
DISPLAY INVISIBLE (-2275 1950);
FORCEADD OFFPAGE..2
(-2450 1825);
FORCEPROP 2 LAST $XR0 113 
J 0
(-2261 1825);
DISPLAY 0.638298 (-2261 1825);
PAINT MONO (-2261 1825);
FORCEPROP 2 LAST CDS_LIB mstr_standard
J 0
(-2450 1825);
PAINT ORANGE (-2450 1825);
DISPLAY INVISIBLE (-2450 1825);
FORCEPROP 1 LAST OFFPAGE TRUE
J 0
(-2125 1700);
DISPLAY 1.170213 (-2125 1700);
PAINT GREEN (-2125 1700);
DISPLAY INVISIBLE (-2125 1700);
FORCEPROP 1 LAST COMMENT_BODY TRUE
J 0
(-2495 1730);
DISPLAY 1.170213 (-2495 1730);
PAINT GREEN (-2495 1730);
DISPLAY INVISIBLE (-2495 1730);
FORCEPROP 2 LAST PATH I191
J 0
(-2275 1900);
DISPLAY 1.021277 (-2275 1900);
PAINT ORANGE (-2275 1900);
DISPLAY INVISIBLE (-2275 1900);
FORCEADD OFFPAGE..2
(-2450 1775);
FORCEPROP 2 LAST $XR0 113 
J 0
(-2261 1775);
DISPLAY 0.638298 (-2261 1775);
PAINT MONO (-2261 1775);
FORCEPROP 2 LAST CDS_LIB mstr_standard
J 0
(-2450 1775);
PAINT ORANGE (-2450 1775);
DISPLAY INVISIBLE (-2450 1775);
FORCEPROP 1 LAST OFFPAGE TRUE
J 0
(-2125 1650);
DISPLAY 1.170213 (-2125 1650);
PAINT GREEN (-2125 1650);
DISPLAY INVISIBLE (-2125 1650);
FORCEPROP 1 LAST COMMENT_BODY TRUE
J 0
(-2495 1680);
DISPLAY 1.170213 (-2495 1680);
PAINT GREEN (-2495 1680);
DISPLAY INVISIBLE (-2495 1680);
FORCEPROP 2 LAST PATH I192
J 0
(-2275 1850);
DISPLAY 1.021277 (-2275 1850);
PAINT ORANGE (-2275 1850);
DISPLAY INVISIBLE (-2275 1850);
FORCEADD RES..2
(-7225 2675);
FORCEPROP 1 LASTPIN (-7225 2775) $PN 1
J 0
(-7220 2737);
DISPLAY 0.617021 (-7220 2737);
PAINT ORANGE (-7220 2737);
FORCEPROP 1 LAST TOLERANCE 1%
J 0
(-7180 2700);
DISPLAY 0.617021 (-7180 2700);
PAINT SKYBLUE (-7180 2700);
FORCEPROP 1 LASTPIN (-7225 2575) $PN 2
J 0
(-7220 2585);
DISPLAY 0.617021 (-7220 2585);
PAINT ORANGE (-7220 2585);
FORCEPROP 1 LAST MATERIAL CHIP
J 0
(-7185 2600);
DISPLAY 0.617021 (-7185 2600);
PAINT SKYBLUE (-7185 2600);
FORCEPROP 1 LAST PACK_TYPE 0402
J 0
(-7185 2500);
DISPLAY 0.617021 (-7185 2500);
PAINT SKYBLUE (-7185 2500);
FORCEPROP 1 LAST PART_NUMBER G21796-072
J 0
(-7185 2550);
DISPLAY 0.617021 (-7185 2550);
PAINT BLUE (-7185 2550);
FORCEPROP 1 LAST LOCATION R7D42
J 0
(-7180 2800);
DISPLAY 0.617021 (-7180 2800);
PAINT AQUA (-7180 2800);
FORCEPROP 1 LAST VALUE 4.75K
J 0
(-7180 2750);
DISPLAY 0.617021 (-7180 2750);
PAINT SKYBLUE (-7180 2750);
FORCEPROP 1 LAST WATTAGE 1/16W
J 0
(-7185 2650);
DISPLAY 0.617021 (-7185 2650);
PAINT SKYBLUE (-7185 2650);
FORCEPROP 2 LAST SEC_TYPE 0402
J 0
(-7175 2900);
DISPLAY 1.021277 (-7175 2900);
PAINT ORANGE (-7175 2900);
DISPLAY INVISIBLE (-7175 2900);
FORCEPROP 2 LAST CDS_LIB mstr_discrete
J 0
(-7225 2675);
PAINT ORANGE (-7225 2675);
DISPLAY INVISIBLE (-7225 2675);
FORCEPROP 2 LAST SEC 1
J 0
(-7175 2900);
DISPLAY 0.680851 (-7175 2900);
PAINT MONO (-7175 2900);
DISPLAY INVISIBLE (-7175 2900);
FORCEPROP 0 LAST ROOM CPLD
J 0
(-7175 2900);
DISPLAY 1.021277 (-7175 2900);
PAINT ORANGE (-7175 2900);
DISPLAY INVISIBLE (-7175 2900);
FORCEPROP 1 LAST PATH I193
J 0
(-7175 2850);
DISPLAY 0.978723 (-7175 2850);
PAINT WHITE (-7175 2850);
DISPLAY INVISIBLE (-7175 2850);
FORCEADD P3V3_STBY..1
(-7225 2900);
FORCEPROP 3 LASTPIN (-7225 2850) SIG_NAME P3V3_STBY\g
J 0
(-7215 2860);
DISPLAY 0.659574 (-7215 2860);
PAINT MONO (-7215 2860);
DISPLAY INVISIBLE (-7215 2860);
FORCEPROP 2 LAST CDS_LIB mstr_symbols
J 0
(-7225 2900);
PAINT ORANGE (-7225 2900);
DISPLAY INVISIBLE (-7225 2900);
FORCEPROP 1 LAST SIZE 1B
J 0
(-7180 2922);
DISPLAY 0.340426 (-7180 2922);
PAINT GREEN (-7180 2922);
DISPLAY INVISIBLE (-7180 2922);
FORCEPROP 1 LAST BODY_TYPE PLUMBING
J 0
(-7270 2857);
DISPLAY 0.340426 (-7270 2857);
PAINT GREEN (-7270 2857);
DISPLAY INVISIBLE (-7270 2857);
FORCEPROP 1 LAST HDL_POWER P3V3_STBY
J 0
(-7525 2775);
DISPLAY 0.872340 (-7525 2775);
PAINT ORANGE (-7525 2775);
DISPLAY INVISIBLE (-7525 2775);
FORCEPROP 1 LAST VOLTAGE 3.3V
J 0
(-7270 2857);
DISPLAY 0.340426 (-7270 2857);
PAINT SKYBLUE (-7270 2857);
DISPLAY INVISIBLE (-7270 2857);
FORCEPROP 1 LAST PATH I194
J 0
(-7180 2902);
DISPLAY 0.340426 (-7180 2902);
PAINT GREEN (-7180 2902);
DISPLAY INVISIBLE (-7180 2902);
FORCEADD RES..2
(-1700 2200);
FORCEPROP 1 LAST PACK_TYPE 0402
J 0
(-1660 2025);
DISPLAY 0.617021 (-1660 2025);
PAINT SKYBLUE (-1660 2025);
FORCEPROP 1 LAST PART_NUMBER G21796-072
J 0
(-1660 2075);
DISPLAY 0.617021 (-1660 2075);
PAINT BLUE (-1660 2075);
FORCEPROP 1 LAST MATERIAL CHIP
J 0
(-1660 2125);
DISPLAY 0.617021 (-1660 2125);
PAINT SKYBLUE (-1660 2125);
FORCEPROP 1 LAST WATTAGE 1/16W
J 0
(-1660 2175);
DISPLAY 0.617021 (-1660 2175);
PAINT SKYBLUE (-1660 2175);
FORCEPROP 1 LAST TOLERANCE 1%
J 0
(-1655 2225);
DISPLAY 0.617021 (-1655 2225);
PAINT SKYBLUE (-1655 2225);
FORCEPROP 1 LASTPIN (-1700 2300) $PN 1
J 0
(-1695 2262);
DISPLAY 0.617021 (-1695 2262);
PAINT ORANGE (-1695 2262);
FORCEPROP 1 LAST VALUE 4.75K
J 0
(-1655 2275);
DISPLAY 0.617021 (-1655 2275);
PAINT SKYBLUE (-1655 2275);
FORCEPROP 1 LASTPIN (-1700 2100) $PN 2
J 0
(-1695 2110);
DISPLAY 0.617021 (-1695 2110);
PAINT ORANGE (-1695 2110);
FORCEPROP 1 LAST LOCATION R4W1
J 0
(-1655 2325);
DISPLAY 0.617021 (-1655 2325);
PAINT AQUA (-1655 2325);
FORCEPROP 1 LAST PATH I195
J 0
(-1650 2375);
DISPLAY 0.978723 (-1650 2375);
PAINT WHITE (-1650 2375);
DISPLAY INVISIBLE (-1650 2375);
FORCEPROP 0 LAST ROOM CPLD
J 0
(-1650 2425);
DISPLAY 1.021277 (-1650 2425);
PAINT ORANGE (-1650 2425);
DISPLAY INVISIBLE (-1650 2425);
FORCEPROP 2 LAST SEC 1
J 0
(-1650 2425);
DISPLAY 0.680851 (-1650 2425);
PAINT MONO (-1650 2425);
DISPLAY INVISIBLE (-1650 2425);
FORCEPROP 2 LAST CDS_LIB mstr_discrete
J 0
(-1700 2200);
PAINT ORANGE (-1700 2200);
DISPLAY INVISIBLE (-1700 2200);
FORCEPROP 2 LAST SEC_TYPE 0402
J 0
(-1650 2425);
DISPLAY 1.021277 (-1650 2425);
PAINT ORANGE (-1650 2425);
DISPLAY INVISIBLE (-1650 2425);
FORCEADD P3V3_STBY..1
(-1700 2425);
FORCEPROP 3 LASTPIN (-1700 2375) SIG_NAME P3V3_STBY\g
J 0
(-1690 2385);
DISPLAY 0.659574 (-1690 2385);
PAINT MONO (-1690 2385);
DISPLAY INVISIBLE (-1690 2385);
FORCEPROP 1 LAST PATH I196
J 0
(-1655 2427);
DISPLAY 0.340426 (-1655 2427);
PAINT GREEN (-1655 2427);
DISPLAY INVISIBLE (-1655 2427);
FORCEPROP 1 LAST VOLTAGE 3.3V
J 0
(-1745 2382);
DISPLAY 0.340426 (-1745 2382);
PAINT SKYBLUE (-1745 2382);
DISPLAY INVISIBLE (-1745 2382);
FORCEPROP 1 LAST HDL_POWER P3V3_STBY
J 0
(-2000 2300);
DISPLAY 0.872340 (-2000 2300);
PAINT ORANGE (-2000 2300);
DISPLAY INVISIBLE (-2000 2300);
FORCEPROP 1 LAST BODY_TYPE PLUMBING
J 0
(-1745 2382);
DISPLAY 0.340426 (-1745 2382);
PAINT GREEN (-1745 2382);
DISPLAY INVISIBLE (-1745 2382);
FORCEPROP 1 LAST SIZE 1B
J 0
(-1655 2447);
DISPLAY 0.340426 (-1655 2447);
PAINT GREEN (-1655 2447);
DISPLAY INVISIBLE (-1655 2447);
FORCEPROP 2 LAST CDS_LIB mstr_symbols
J 0
(-1700 2425);
PAINT ORANGE (-1700 2425);
DISPLAY INVISIBLE (-1700 2425);
FORCEADD RES..1
(-3100 1375);
FORCEPROP 1 LAST WATTAGE 1/16W
J 0
(-3350 1325);
DISPLAY 0.638298 (-3350 1325);
PAINT SKYBLUE (-3350 1325);
FORCEPROP 1 LAST LOCATION R1W28
J 0
(-3550 1325);
DISPLAY 0.617021 (-3550 1325);
PAINT AQUA (-3550 1325);
FORCEPROP 1 LAST PART_NUMBER G21497-005
J 0
(-2975 1325);
DISPLAY 0.617021 (-2975 1325);
PAINT BLUE (-2975 1325);
FORCEPROP 1 LAST TOLERANCE 5%
J 0
(-3075 1325);
DISPLAY 0.617021 (-3075 1325);
PAINT SKYBLUE (-3075 1325);
FORCEPROP 1 LAST VALUE 0.0
J 0
(-3175 1325);
DISPLAY 0.617021 (-3175 1325);
PAINT SKYBLUE (-3175 1325);
FORCEPROP 1 LAST MATERIAL CHIP
J 0
(-2725 1325);
DISPLAY 0.617021 (-2725 1325);
PAINT SKYBLUE (-2725 1325);
FORCEPROP 0 LAST SEC_TYPE 0402
J 0
(-2600 1325);
DISPLAY 0.638298 (-2600 1325);
PAINT SKYBLUE (-2600 1325);
FORCEPROP 1 LASTPIN (-3000 1375) $PN 2
J 0
(-3038 1387);
DISPLAY 0.617021 (-3038 1387);
PAINT ORANGE (-3038 1387);
FORCEPROP 1 LASTPIN (-3200 1375) $PN 1
J 0
(-3188 1387);
DISPLAY 0.617021 (-3188 1387);
PAINT ORANGE (-3188 1387);
FORCEPROP 1 LAST PATH I197
J 0
(-3150 1525);
DISPLAY 0.978723 (-3150 1525);
PAINT WHITE (-3150 1525);
DISPLAY INVISIBLE (-3150 1525);
FORCEPROP 2 LAST CDS_LIB mstr_discrete
J 0
(-3100 1375);
PAINT ORANGE (-3100 1375);
DISPLAY INVISIBLE (-3100 1375);
FORCEPROP 2 LAST SEC 1
J 0
(-3150 1575);
DISPLAY 0.680851 (-3150 1575);
PAINT MONO (-3150 1575);
DISPLAY INVISIBLE (-3150 1575);
FORCEPROP 0 LAST ROOM BMC
J 0
(-3150 1575);
DISPLAY 1.021277 (-3150 1575);
PAINT ORANGE (-3150 1575);
DISPLAY INVISIBLE (-3150 1575);
FORCEPROP 0 LAST BOM_COST SM_CONTROLLER
J 0
(-3150 1675);
DISPLAY 1.021277 (-3150 1675);
PAINT ORANGE (-3150 1675);
DISPLAY INVISIBLE (-3150 1675);
FORCEPROP 1 LAST PACK_TYPE 0402
J 0
(-2850 1225);
DISPLAY 0.978723 (-2850 1225);
PAINT SKYBLUE (-2850 1225);
DISPLAY INVISIBLE (-2850 1225);
FORCEPROP 0 LAST CDS_SEC 1
J 0
(-2975 1425);
PAINT MONO (-2975 1425);
DISPLAY INVISIBLE (-2975 1425);
FORCEPROP 2 LAST CDS_LOCATION R1W28
J 0
(-3500 1375);
DISPLAY 0.617021 (-3500 1375);
PAINT AQUA (-3500 1375);
DISPLAY INVISIBLE (-3500 1375);
FORCEADD RES..1
(-6200 3525);
FORCEPROP 1 LASTPIN (-6100 3525) $PN 2
J 0
(-6138 3537);
DISPLAY 0.617021 (-6138 3537);
PAINT ORANGE (-6138 3537);
FORCEPROP 1 LASTPIN (-6300 3525) $PN 1
J 0
(-6288 3537);
DISPLAY 0.617021 (-6288 3537);
PAINT ORANGE (-6288 3537);
FORCEPROP 1 LAST LOCATION R1W29
J 0
(-6350 3575);
DISPLAY 0.617021 (-6350 3575);
PAINT AQUA (-6350 3575);
FORCEPROP 1 LAST VALUE 0.0
J 0
(-6175 3575);
DISPLAY 0.617021 (-6175 3575);
PAINT SKYBLUE (-6175 3575);
FORCEPROP 1 LAST TOLERANCE 5%
J 0
(-6075 3575);
DISPLAY 0.617021 (-6075 3575);
PAINT SKYBLUE (-6075 3575);
FORCEPROP 1 LAST PART_NUMBER G21497-005
J 0
(-5975 3575);
DISPLAY 0.617021 (-5975 3575);
PAINT BLUE (-5975 3575);
FORCEPROP 1 LAST WATTAGE 1/16W
J 0
(-5450 3575);
DISPLAY 0.638298 (-5450 3575);
PAINT SKYBLUE (-5450 3575);
FORCEPROP 1 LAST MATERIAL CHIP
J 0
(-5725 3575);
DISPLAY 0.617021 (-5725 3575);
PAINT SKYBLUE (-5725 3575);
FORCEPROP 0 LAST SEC_TYPE 0402
J 0
(-5600 3575);
DISPLAY 0.638298 (-5600 3575);
PAINT SKYBLUE (-5600 3575);
FORCEPROP 2 LAST CDS_LIB mstr_discrete
J 0
(-6200 3525);
PAINT ORANGE (-6200 3525);
DISPLAY INVISIBLE (-6200 3525);
FORCEPROP 2 LAST SEC 1
J 0
(-6250 3725);
DISPLAY 0.680851 (-6250 3725);
PAINT MONO (-6250 3725);
DISPLAY INVISIBLE (-6250 3725);
FORCEPROP 0 LAST ROOM BMC
J 0
(-6250 3725);
DISPLAY 1.021277 (-6250 3725);
PAINT ORANGE (-6250 3725);
DISPLAY INVISIBLE (-6250 3725);
FORCEPROP 0 LAST BOM_COST SM_CONTROLLER
J 0
(-6250 3825);
DISPLAY 1.021277 (-6250 3825);
PAINT ORANGE (-6250 3825);
DISPLAY INVISIBLE (-6250 3825);
FORCEPROP 1 LAST PACK_TYPE 0402
J 0
(-5950 3375);
DISPLAY 0.978723 (-5950 3375);
PAINT SKYBLUE (-5950 3375);
DISPLAY INVISIBLE (-5950 3375);
FORCEPROP 0 LAST CDS_SEC 1
J 0
(-6075 3575);
PAINT MONO (-6075 3575);
DISPLAY INVISIBLE (-6075 3575);
FORCEPROP 1 LAST PATH I198
J 0
(-6250 3675);
DISPLAY 0.978723 (-6250 3675);
PAINT WHITE (-6250 3675);
DISPLAY INVISIBLE (-6250 3675);
FORCEPROP 2 LAST CDS_LOCATION R1W29
J 0
(-6600 3525);
DISPLAY 0.617021 (-6600 3525);
PAINT AQUA (-6600 3525);
DISPLAY INVISIBLE (-6600 3525);
FORCEADD OFFPAGE..2
R 2
(-7200 3525);
FORCEPROP 2 LAST $XR1 118 
J 0
(-7605 3525);
DISPLAY 0.638298 (-7605 3525);
PAINT MONO (-7605 3525);
FORCEPROP 2 LAST $XR0 156 
J 0
(-7485 3525);
DISPLAY 0.638298 (-7485 3525);
PAINT MONO (-7485 3525);
FORCEPROP 2 LAST PATH I199
J 0
(-7450 3575);
DISPLAY 1.021277 (-7450 3575);
PAINT ORANGE (-7450 3575);
DISPLAY INVISIBLE (-7450 3575);
FORCEPROP 1 LAST COMMENT_BODY TRUE
J 2
(-7155 3430);
DISPLAY 1.170213 (-7155 3430);
PAINT GREEN (-7155 3430);
DISPLAY INVISIBLE (-7155 3430);
FORCEPROP 1 LAST OFFPAGE TRUE
J 2
(-7525 3400);
DISPLAY 1.170213 (-7525 3400);
PAINT GREEN (-7525 3400);
DISPLAY INVISIBLE (-7525 3400);
FORCEPROP 2 LAST CDS_LIB mstr_standard
J 0
(-7200 3525);
PAINT ORANGE (-7200 3525);
DISPLAY INVISIBLE (-7200 3525);
FORCEADD OFFPAGE..2
(-2450 4325);
FORCEPROP 2 LAST $XR3 120 
J 0
(-1931 4325);
DISPLAY 0.638298 (-1931 4325);
PAINT MONO (-1931 4325);
FORCEPROP 2 LAST $XR2 157 
J 0
(-2051 4325);
DISPLAY 0.638298 (-2051 4325);
PAINT MONO (-2051 4325);
FORCEPROP 2 LAST $XR1 156 
J 0
(-2171 4325);
DISPLAY 0.638298 (-2171 4325);
PAINT MONO (-2171 4325);
FORCEPROP 2 LAST $XR0 89 
J 0
(-2261 4325);
DISPLAY 0.638298 (-2261 4325);
PAINT MONO (-2261 4325);
FORCEPROP 2 LAST PATH I2
J 0
(-2250 4375);
DISPLAY 1.021277 (-2250 4375);
PAINT ORANGE (-2250 4375);
DISPLAY INVISIBLE (-2250 4375);
FORCEPROP 1 LAST COMMENT_BODY TRUE
J 0
(-2495 4230);
DISPLAY 1.170213 (-2495 4230);
PAINT GREEN (-2495 4230);
DISPLAY INVISIBLE (-2495 4230);
FORCEPROP 1 LAST OFFPAGE TRUE
J 0
(-2125 4200);
DISPLAY 1.170213 (-2125 4200);
PAINT GREEN (-2125 4200);
DISPLAY INVISIBLE (-2125 4200);
FORCEPROP 2 LAST CDS_LIB mstr_standard
J 0
(-2450 4325);
PAINT ORANGE (-2450 4325);
DISPLAY INVISIBLE (-2450 4325);
FORCEADD OFFPAGE..2
(-2450 3375);
FORCEPROP 2 LAST $XR0 144 
J 0
(-2261 3375);
DISPLAY 0.638298 (-2261 3375);
PAINT MONO (-2261 3375);
FORCEPROP 2 LAST CDS_LIB mstr_standard
J 0
(-2450 3375);
PAINT ORANGE (-2450 3375);
DISPLAY INVISIBLE (-2450 3375);
FORCEPROP 1 LAST OFFPAGE TRUE
J 0
(-2125 3250);
DISPLAY 1.170213 (-2125 3250);
PAINT GREEN (-2125 3250);
DISPLAY INVISIBLE (-2125 3250);
FORCEPROP 1 LAST COMMENT_BODY TRUE
J 0
(-2495 3280);
DISPLAY 1.170213 (-2495 3280);
PAINT GREEN (-2495 3280);
DISPLAY INVISIBLE (-2495 3280);
FORCEPROP 2 LAST PATH I22
J 0
(-2250 3425);
DISPLAY 1.021277 (-2250 3425);
PAINT ORANGE (-2250 3425);
DISPLAY INVISIBLE (-2250 3425);
FORCEADD OFFPAGE..4
(-2450 3225);
FORCEPROP 2 LAST $XR0 192 
J 0
(-2264 3225);
DISPLAY 0.638298 (-2264 3225);
PAINT MONO (-2264 3225);
FORCEPROP 2 LAST CDS_LIB mstr_standard
J 0
(-2450 3225);
PAINT ORANGE (-2450 3225);
DISPLAY INVISIBLE (-2450 3225);
FORCEPROP 1 LAST OFFPAGE TRUE
J 0
(-2125 3100);
DISPLAY 1.170213 (-2125 3100);
PAINT GREEN (-2125 3100);
DISPLAY INVISIBLE (-2125 3100);
FORCEPROP 1 LAST COMMENT_BODY TRUE
J 0
(-2475 3125);
DISPLAY 1.170213 (-2475 3125);
PAINT GREEN (-2475 3125);
DISPLAY INVISIBLE (-2475 3125);
FORCEPROP 2 LAST PATH I24
J 0
(-2250 3275);
DISPLAY 1.021277 (-2250 3275);
PAINT ORANGE (-2250 3275);
DISPLAY INVISIBLE (-2250 3275);
FORCEADD OFFPAGE..4
(-2450 3125);
FORCEPROP 2 LAST $XR0 189 
J 0
(-2264 3125);
DISPLAY 0.638298 (-2264 3125);
PAINT MONO (-2264 3125);
FORCEPROP 2 LAST CDS_LIB mstr_standard
J 2
(-2450 3125);
PAINT ORANGE (-2450 3125);
DISPLAY INVISIBLE (-2450 3125);
FORCEPROP 1 LAST OFFPAGE TRUE
J 0
(-2125 3000);
DISPLAY 1.170213 (-2125 3000);
PAINT GREEN (-2125 3000);
DISPLAY INVISIBLE (-2125 3000);
FORCEPROP 1 LAST COMMENT_BODY TRUE
J 0
(-2475 3025);
DISPLAY 1.170213 (-2475 3025);
PAINT GREEN (-2475 3025);
DISPLAY INVISIBLE (-2475 3025);
FORCEPROP 2 LAST PATH I26
J 0
(-2250 3175);
DISPLAY 1.021277 (-2250 3175);
PAINT ORANGE (-2250 3175);
DISPLAY INVISIBLE (-2250 3175);
FORCEADD OFFPAGE..4
(-2450 3075);
FORCEPROP 2 LAST $XR0 189 
J 0
(-2264 3075);
DISPLAY 0.638298 (-2264 3075);
PAINT MONO (-2264 3075);
FORCEPROP 2 LAST CDS_LIB mstr_standard
J 0
(-2450 3075);
PAINT ORANGE (-2450 3075);
DISPLAY INVISIBLE (-2450 3075);
FORCEPROP 1 LAST OFFPAGE TRUE
J 0
(-2125 2950);
DISPLAY 1.170213 (-2125 2950);
PAINT GREEN (-2125 2950);
DISPLAY INVISIBLE (-2125 2950);
FORCEPROP 1 LAST COMMENT_BODY TRUE
J 0
(-2475 2975);
DISPLAY 1.170213 (-2475 2975);
PAINT GREEN (-2475 2975);
DISPLAY INVISIBLE (-2475 2975);
FORCEPROP 2 LAST PATH I27
J 0
(-2250 3125);
DISPLAY 1.021277 (-2250 3125);
PAINT ORANGE (-2250 3125);
DISPLAY INVISIBLE (-2250 3125);
FORCEADD OFFPAGE..4
(-2450 2575);
FORCEPROP 2 LAST $XR2 184 
J 0
(-2024 2575);
DISPLAY 0.638298 (-2024 2575);
PAINT MONO (-2024 2575);
FORCEPROP 2 LAST $XR1 164 
J 0
(-2144 2575);
DISPLAY 0.638298 (-2144 2575);
PAINT MONO (-2144 2575);
FORCEPROP 2 LAST $XR0 167 
J 0
(-2264 2575);
DISPLAY 0.638298 (-2264 2575);
PAINT MONO (-2264 2575);
FORCEPROP 2 LAST CDS_LIB mstr_standard
J 2
(-2450 2575);
PAINT ORANGE (-2450 2575);
DISPLAY INVISIBLE (-2450 2575);
FORCEPROP 1 LAST OFFPAGE TRUE
J 0
(-2125 2450);
DISPLAY 1.170213 (-2125 2450);
PAINT GREEN (-2125 2450);
DISPLAY INVISIBLE (-2125 2450);
FORCEPROP 1 LAST COMMENT_BODY TRUE
J 0
(-2475 2475);
DISPLAY 1.170213 (-2475 2475);
PAINT GREEN (-2475 2475);
DISPLAY INVISIBLE (-2475 2475);
FORCEPROP 2 LAST PATH I33
J 0
(-2250 2625);
DISPLAY 1.021277 (-2250 2625);
PAINT ORANGE (-2250 2625);
DISPLAY INVISIBLE (-2250 2625);
FORCEADD OFFPAGE..2
(-2450 2325);
FORCEPROP 2 LAST $XR0 181 
J 0
(-2261 2325);
DISPLAY 0.638298 (-2261 2325);
PAINT MONO (-2261 2325);
FORCEPROP 2 LAST CDS_LIB mstr_standard
J 0
(-2450 2325);
PAINT ORANGE (-2450 2325);
DISPLAY INVISIBLE (-2450 2325);
FORCEPROP 1 LAST OFFPAGE TRUE
J 0
(-2125 2200);
DISPLAY 1.170213 (-2125 2200);
PAINT GREEN (-2125 2200);
DISPLAY INVISIBLE (-2125 2200);
FORCEPROP 1 LAST COMMENT_BODY TRUE
J 0
(-2495 2230);
DISPLAY 1.170213 (-2495 2230);
PAINT GREEN (-2495 2230);
DISPLAY INVISIBLE (-2495 2230);
FORCEPROP 2 LAST PATH I38
J 0
(-2250 2375);
DISPLAY 1.021277 (-2250 2375);
PAINT ORANGE (-2250 2375);
DISPLAY INVISIBLE (-2250 2375);
FORCEADD OFFPAGE..4
(-2450 1675);
FORCEPROP 2 LAST $XR4 247 
J 0
(-1784 1675);
DISPLAY 0.638298 (-1784 1675);
PAINT MONO (-1784 1675);
FORCEPROP 2 LAST $XR3 157 
J 0
(-1904 1675);
DISPLAY 0.638298 (-1904 1675);
PAINT MONO (-1904 1675);
FORCEPROP 2 LAST $XR2 118 
J 0
(-2024 1675);
DISPLAY 0.638298 (-2024 1675);
PAINT MONO (-2024 1675);
FORCEPROP 2 LAST $XR1 200 
J 0
(-2144 1675);
DISPLAY 0.638298 (-2144 1675);
PAINT MONO (-2144 1675);
FORCEPROP 2 LAST $XR0 196 
J 0
(-2264 1675);
DISPLAY 0.638298 (-2264 1675);
PAINT MONO (-2264 1675);
FORCEPROP 2 LAST CDS_LIB mstr_standard
J 0
(-2450 1675);
PAINT ORANGE (-2450 1675);
DISPLAY INVISIBLE (-2450 1675);
FORCEPROP 1 LAST OFFPAGE TRUE
J 0
(-2125 1550);
DISPLAY 1.170213 (-2125 1550);
PAINT GREEN (-2125 1550);
DISPLAY INVISIBLE (-2125 1550);
FORCEPROP 1 LAST COMMENT_BODY TRUE
J 0
(-2475 1575);
DISPLAY 1.170213 (-2475 1575);
PAINT GREEN (-2475 1575);
DISPLAY INVISIBLE (-2475 1575);
FORCEPROP 2 LAST PATH I47
J 0
(-2250 1725);
DISPLAY 1.021277 (-2250 1725);
PAINT ORANGE (-2250 1725);
DISPLAY INVISIBLE (-2250 1725);
FORCEADD OFFPAGE..4
(-2450 1625);
FORCEPROP 2 LAST $XR0 192 
J 0
(-2264 1625);
DISPLAY 0.638298 (-2264 1625);
PAINT MONO (-2264 1625);
FORCEPROP 2 LAST CDS_LIB mstr_standard
J 2
(-2450 1625);
PAINT ORANGE (-2450 1625);
DISPLAY INVISIBLE (-2450 1625);
FORCEPROP 1 LAST OFFPAGE TRUE
J 0
(-2125 1500);
DISPLAY 1.170213 (-2125 1500);
PAINT GREEN (-2125 1500);
DISPLAY INVISIBLE (-2125 1500);
FORCEPROP 1 LAST COMMENT_BODY TRUE
J 0
(-2475 1525);
DISPLAY 1.170213 (-2475 1525);
PAINT GREEN (-2475 1525);
DISPLAY INVISIBLE (-2475 1525);
FORCEPROP 2 LAST PATH I49
J 0
(-2250 1675);
DISPLAY 1.021277 (-2250 1675);
PAINT ORANGE (-2250 1675);
DISPLAY INVISIBLE (-2250 1675);
FORCEADD LCMXO2_A..5
(-4475 2725);
FORCEPROP 2 LASTPIN (-5075 3375) $PN G13
J 2
(-5085 3385);
DISPLAY 0.617021 (-5085 3385);
PAINT ORANGE (-5085 3385);
FORCEPROP 2 LASTPIN (-5075 3275) $PN G15
J 2
(-5085 3285);
DISPLAY 0.617021 (-5085 3285);
PAINT ORANGE (-5085 3285);
FORCEPROP 2 LASTPIN (-5075 3525) $PN F14
J 2
(-5085 3535);
DISPLAY 0.617021 (-5085 3535);
PAINT ORANGE (-5085 3535);
FORCEPROP 2 LASTPIN (-5075 3025) $PN G16
J 2
(-5085 3035);
DISPLAY 0.617021 (-5085 3035);
PAINT ORANGE (-5085 3035);
FORCEPROP 2 LASTPIN (-3875 2675) $PN F8
J 0
(-3865 2685);
DISPLAY 0.617021 (-3865 2685);
PAINT ORANGE (-3865 2685);
FORCEPROP 2 LASTPIN (-3875 2075) $PN C10
J 0
(-3865 2085);
DISPLAY 0.617021 (-3865 2085);
PAINT ORANGE (-3865 2085);
FORCEPROP 2 LASTPIN (-3875 2025) $PN B10
J 0
(-3865 2035);
DISPLAY 0.617021 (-3865 2035);
PAINT ORANGE (-3865 2035);
FORCEPROP 2 LASTPIN (-3875 1625) $PN A12
J 0
(-3865 1635);
DISPLAY 0.617021 (-3865 1635);
PAINT ORANGE (-3865 1635);
FORCEPROP 2 LASTPIN (-3875 1575) $PN B13
J 0
(-3865 1585);
DISPLAY 0.617021 (-3865 1585);
PAINT ORANGE (-3865 1585);
FORCEPROP 2 LASTPIN (-3875 1525) $PN A14
J 0
(-3865 1535);
DISPLAY 0.617021 (-3865 1535);
PAINT ORANGE (-3865 1535);
FORCEPROP 2 LASTPIN (-3875 1925) $PN A11
J 0
(-3865 1935);
DISPLAY 0.617021 (-3865 1935);
PAINT ORANGE (-3865 1935);
FORCEPROP 2 LASTPIN (-5075 2025) $PN L16
J 2
(-5085 2035);
DISPLAY 0.617021 (-5085 2035);
PAINT ORANGE (-5085 2035);
FORCEPROP 1 LAST LOCATION U8D7
J 0
(-5049 4501);
DISPLAY 0.617021 (-5049 4501);
PAINT AQUA (-5049 4501);
FORCEPROP 1 LAST PART_NUMBER H63395-001
J 0
(-5025 975);
DISPLAY 0.617021 (-5025 975);
PAINT BLUE (-5025 975);
FORCEPROP 1 LAST MATERIAL IC
J 0
(-5049 4451);
DISPLAY 0.617021 (-5049 4451);
PAINT SKYBLUE (-5049 4451);
FORCEPROP 2 LASTPIN (-3875 3425) $PN C7
J 0
(-3865 3435);
DISPLAY 0.617021 (-3865 3435);
PAINT ORANGE (-3865 3435);
FORCEPROP 2 LASTPIN (-3875 3575) $PN A6
J 0
(-3865 3585);
DISPLAY 0.617021 (-3865 3585);
PAINT ORANGE (-3865 3585);
FORCEPROP 2 LASTPIN (-3875 3625) $PN C6
J 0
(-3865 3635);
DISPLAY 0.617021 (-3865 3635);
PAINT ORANGE (-3865 3635);
FORCEPROP 2 LASTPIN (-3875 3675) $PN E7
J 0
(-3865 3685);
DISPLAY 0.617021 (-3865 3685);
PAINT ORANGE (-3865 3685);
FORCEPROP 2 LASTPIN (-5075 4275) $PN E15
J 2
(-5085 4285);
DISPLAY 0.617021 (-5085 4285);
PAINT ORANGE (-5085 4285);
FORCEPROP 2 LASTPIN (-5075 4325) $PN D14
J 2
(-5085 4335);
DISPLAY 0.617021 (-5085 4335);
PAINT ORANGE (-5085 4335);
FORCEPROP 2 LASTPIN (-3875 1425) $PN C12
J 0
(-3865 1435);
DISPLAY 0.617021 (-3865 1435);
PAINT ORANGE (-3865 1435);
FORCEPROP 2 LASTPIN (-3875 2275) $PN E11
J 0
(-3865 2285);
DISPLAY 0.617021 (-3865 2285);
PAINT ORANGE (-3865 2285);
FORCEPROP 2 LASTPIN (-3875 2425) $PN B9
J 0
(-3865 2435);
DISPLAY 0.617021 (-3865 2435);
PAINT ORANGE (-3865 2435);
FORCEPROP 2 LASTPIN (-3875 1125) $PN C13
J 0
(-3865 1135);
DISPLAY 0.617021 (-3865 1135);
PAINT ORANGE (-3865 1135);
FORCEPROP 2 LASTPIN (-3875 1175) $PN A13
J 0
(-3865 1185);
DISPLAY 0.617021 (-3865 1185);
PAINT ORANGE (-3865 1185);
FORCEPROP 2 LASTPIN (-3875 1225) $PN A15
J 0
(-3865 1235);
DISPLAY 0.617021 (-3865 1235);
PAINT ORANGE (-3865 1235);
FORCEPROP 2 LASTPIN (-3875 1275) $PN B14
J 0
(-3865 1285);
DISPLAY 0.617021 (-3865 1285);
PAINT ORANGE (-3865 1285);
FORCEPROP 2 LASTPIN (-3875 1675) $PN B11
J 0
(-3865 1685);
DISPLAY 0.617021 (-3865 1685);
PAINT ORANGE (-3865 1685);
FORCEPROP 2 LASTPIN (-3875 1775) $PN D11
J 0
(-3865 1785);
DISPLAY 0.617021 (-3865 1785);
PAINT ORANGE (-3865 1785);
FORCEPROP 2 LASTPIN (-3875 1825) $PN F10
J 0
(-3865 1835);
DISPLAY 0.617021 (-3865 1835);
PAINT ORANGE (-3865 1835);
FORCEPROP 2 LASTPIN (-3875 1875) $PN C11
J 0
(-3865 1885);
DISPLAY 0.617021 (-3865 1885);
PAINT ORANGE (-3865 1885);
FORCEPROP 2 LASTPIN (-3875 2325) $PN F9
J 0
(-3865 2335);
DISPLAY 0.617021 (-3865 2335);
PAINT ORANGE (-3865 2335);
FORCEPROP 2 LASTPIN (-3875 2375) $PN A10
J 0
(-3865 2385);
DISPLAY 0.617021 (-3865 2385);
PAINT ORANGE (-3865 2385);
FORCEPROP 2 LASTPIN (-3875 2525) $PN C9
J 0
(-3865 2535);
DISPLAY 0.617021 (-3865 2535);
PAINT ORANGE (-3865 2535);
FORCEPROP 2 LASTPIN (-3875 2625) $PN D9
J 0
(-3865 2635);
DISPLAY 0.617021 (-3865 2635);
PAINT ORANGE (-3865 2635);
FORCEPROP 2 LASTPIN (-3875 2825) $PN E9
J 0
(-3865 2835);
DISPLAY 0.617021 (-3865 2835);
PAINT ORANGE (-3865 2835);
FORCEPROP 2 LASTPIN (-3875 2875) $PN D8
J 0
(-3865 2885);
DISPLAY 0.617021 (-3865 2885);
PAINT ORANGE (-3865 2885);
FORCEPROP 2 LASTPIN (-3875 2925) $PN A8
J 0
(-3865 2935);
DISPLAY 0.617021 (-3865 2935);
PAINT ORANGE (-3865 2935);
FORCEPROP 2 LASTPIN (-3875 2975) $PN C8
J 0
(-3865 2985);
DISPLAY 0.617021 (-3865 2985);
PAINT ORANGE (-3865 2985);
FORCEPROP 2 LASTPIN (-3875 3075) $PN B8
J 0
(-3865 3085);
DISPLAY 0.617021 (-3865 3085);
PAINT ORANGE (-3865 3085);
FORCEPROP 2 LASTPIN (-3875 3125) $PN A7
J 0
(-3865 3135);
DISPLAY 0.617021 (-3865 3135);
PAINT ORANGE (-3865 3135);
FORCEPROP 2 LASTPIN (-3875 3175) $PN E8
J 0
(-3865 3185);
DISPLAY 0.617021 (-3865 3185);
PAINT ORANGE (-3865 3185);
FORCEPROP 2 LASTPIN (-3875 3225) $PN F7
J 0
(-3865 3235);
DISPLAY 0.617021 (-3865 3235);
PAINT ORANGE (-3865 3235);
FORCEPROP 2 LASTPIN (-3875 3325) $PN D7
J 0
(-3865 3335);
DISPLAY 0.617021 (-3865 3335);
PAINT ORANGE (-3865 3335);
FORCEPROP 2 LASTPIN (-3875 3375) $PN E6
J 0
(-3865 3385);
DISPLAY 0.617021 (-3865 3385);
PAINT ORANGE (-3865 3385);
FORCEPROP 2 LASTPIN (-3875 3475) $PN B7
J 0
(-3865 3485);
DISPLAY 0.617021 (-3865 3485);
PAINT ORANGE (-3865 3485);
FORCEPROP 2 LASTPIN (-3875 3725) $PN D6
J 0
(-3865 3735);
DISPLAY 0.617021 (-3865 3735);
PAINT ORANGE (-3865 3735);
FORCEPROP 2 LASTPIN (-3875 3825) $PN B4
J 0
(-3865 3835);
DISPLAY 0.617021 (-3865 3835);
PAINT ORANGE (-3865 3835);
FORCEPROP 2 LASTPIN (-3875 3875) $PN A3
J 0
(-3865 3885);
DISPLAY 0.617021 (-3865 3885);
PAINT ORANGE (-3865 3885);
FORCEPROP 2 LASTPIN (-3875 3925) $PN B6
J 0
(-3865 3935);
DISPLAY 0.617021 (-3865 3935);
PAINT ORANGE (-3865 3935);
FORCEPROP 2 LASTPIN (-3875 3975) $PN A5
J 0
(-3865 3985);
DISPLAY 0.617021 (-3865 3985);
PAINT ORANGE (-3865 3985);
FORCEPROP 2 LASTPIN (-3875 4075) $PN C5
J 0
(-3865 4085);
DISPLAY 0.617021 (-3865 4085);
PAINT ORANGE (-3865 4085);
FORCEPROP 2 LASTPIN (-3875 4125) $PN A4
J 0
(-3865 4135);
DISPLAY 0.617021 (-3865 4135);
PAINT ORANGE (-3865 4135);
FORCEPROP 2 LASTPIN (-3875 4225) $PN B3
J 0
(-3865 4235);
DISPLAY 0.617021 (-3865 4235);
PAINT ORANGE (-3865 4235);
FORCEPROP 2 LASTPIN (-3875 4275) $PN B5
J 0
(-3865 4285);
DISPLAY 0.617021 (-3865 4285);
PAINT ORANGE (-3865 4285);
FORCEPROP 2 LASTPIN (-3875 4325) $PN C4
J 0
(-3865 4335);
DISPLAY 0.617021 (-3865 4335);
PAINT ORANGE (-3865 4335);
FORCEPROP 2 LASTPIN (-5075 1125) $PN R16
J 2
(-5085 1135);
DISPLAY 0.617021 (-5085 1135);
PAINT ORANGE (-5085 1135);
FORCEPROP 2 LASTPIN (-5075 1175) $PN P15
J 2
(-5085 1185);
DISPLAY 0.617021 (-5085 1185);
PAINT ORANGE (-5085 1185);
FORCEPROP 2 LASTPIN (-5075 1225) $PN N14
J 2
(-5085 1235);
DISPLAY 0.617021 (-5085 1235);
PAINT ORANGE (-5085 1235);
FORCEPROP 2 LASTPIN (-5075 1275) $PN N16
J 2
(-5085 1285);
DISPLAY 0.617021 (-5085 1285);
PAINT ORANGE (-5085 1285);
FORCEPROP 2 LASTPIN (-5075 1375) $PN P16
J 2
(-5085 1385);
DISPLAY 0.617021 (-5085 1385);
PAINT ORANGE (-5085 1385);
FORCEPROP 2 LASTPIN (-5075 1425) $PN N15
J 2
(-5085 1435);
DISPLAY 0.617021 (-5085 1435);
PAINT ORANGE (-5085 1435);
FORCEPROP 2 LASTPIN (-5075 1475) $PN M15
J 2
(-5085 1485);
DISPLAY 0.617021 (-5085 1485);
PAINT ORANGE (-5085 1485);
FORCEPROP 2 LASTPIN (-5075 1525) $PN M14
J 2
(-5085 1535);
DISPLAY 0.617021 (-5085 1535);
PAINT ORANGE (-5085 1535);
FORCEPROP 2 LASTPIN (-5075 1625) $PN L13
J 2
(-5085 1635);
DISPLAY 0.617021 (-5085 1635);
PAINT ORANGE (-5085 1635);
FORCEPROP 2 LASTPIN (-5075 1675) $PN K11
J 2
(-5085 1685);
DISPLAY 0.617021 (-5085 1685);
PAINT ORANGE (-5085 1685);
FORCEPROP 2 LASTPIN (-5075 1725) $PN M16
J 2
(-5085 1735);
DISPLAY 0.617021 (-5085 1735);
PAINT ORANGE (-5085 1735);
FORCEPROP 2 LASTPIN (-5075 1775) $PN L15
J 2
(-5085 1785);
DISPLAY 0.617021 (-5085 1785);
PAINT ORANGE (-5085 1785);
FORCEPROP 2 LASTPIN (-5075 1875) $PN K12
J 2
(-5085 1885);
DISPLAY 0.617021 (-5085 1885);
PAINT ORANGE (-5085 1885);
FORCEPROP 2 LASTPIN (-5075 1925) $PN K13
J 2
(-5085 1935);
DISPLAY 0.617021 (-5085 1935);
PAINT ORANGE (-5085 1935);
FORCEPROP 2 LASTPIN (-5075 1975) $PN L14
J 2
(-5085 1985);
DISPLAY 0.617021 (-5085 1985);
PAINT ORANGE (-5085 1985);
FORCEPROP 2 LASTPIN (-5075 2125) $PN L12
J 2
(-5085 2135);
DISPLAY 0.617021 (-5085 2135);
PAINT ORANGE (-5085 2135);
FORCEPROP 2 LASTPIN (-5075 2175) $PN J11
J 2
(-5085 2185);
DISPLAY 0.617021 (-5085 2185);
PAINT ORANGE (-5085 2185);
FORCEPROP 2 LASTPIN (-5075 2225) $PN K15
J 2
(-5085 2235);
DISPLAY 0.617021 (-5085 2235);
PAINT ORANGE (-5085 2235);
FORCEPROP 2 LASTPIN (-5075 2275) $PN K14
J 2
(-5085 2285);
DISPLAY 0.617021 (-5085 2285);
PAINT ORANGE (-5085 2285);
FORCEPROP 2 LASTPIN (-5075 2375) $PN J13
J 2
(-5085 2385);
DISPLAY 0.617021 (-5085 2385);
PAINT ORANGE (-5085 2385);
FORCEPROP 2 LASTPIN (-5075 2425) $PN H11
J 2
(-5085 2435);
DISPLAY 0.617021 (-5085 2435);
PAINT ORANGE (-5085 2435);
FORCEPROP 2 LASTPIN (-5075 2475) $PN K16
J 2
(-5085 2485);
DISPLAY 0.617021 (-5085 2485);
PAINT ORANGE (-5085 2485);
FORCEPROP 2 LASTPIN (-5075 2525) $PN J15
J 2
(-5085 2535);
DISPLAY 0.617021 (-5085 2535);
PAINT ORANGE (-5085 2535);
FORCEPROP 2 LASTPIN (-5075 2625) $PN J14
J 2
(-5085 2635);
DISPLAY 0.617021 (-5085 2635);
PAINT ORANGE (-5085 2635);
FORCEPROP 2 LASTPIN (-5075 2675) $PN J16
J 2
(-5085 2685);
DISPLAY 0.617021 (-5085 2685);
PAINT ORANGE (-5085 2685);
FORCEPROP 2 LASTPIN (-5075 2725) $PN H16
J 2
(-5085 2735);
DISPLAY 0.617021 (-5085 2735);
PAINT ORANGE (-5085 2735);
FORCEPROP 2 LASTPIN (-5075 2775) $PN H14
J 2
(-5085 2785);
DISPLAY 0.617021 (-5085 2785);
PAINT ORANGE (-5085 2785);
FORCEPROP 2 LASTPIN (-5075 2875) $PN J12
J 2
(-5085 2885);
DISPLAY 0.617021 (-5085 2885);
PAINT ORANGE (-5085 2885);
FORCEPROP 2 LASTPIN (-5075 2925) $PN H13
J 2
(-5085 2935);
DISPLAY 0.617021 (-5085 2935);
PAINT ORANGE (-5085 2935);
FORCEPROP 2 LASTPIN (-5075 2975) $PN H15
J 2
(-5085 2985);
DISPLAY 0.617021 (-5085 2985);
PAINT ORANGE (-5085 2985);
FORCEPROP 2 LASTPIN (-5075 3125) $PN H12
J 2
(-5085 3135);
DISPLAY 0.617021 (-5085 3135);
PAINT ORANGE (-5085 3135);
FORCEPROP 2 LASTPIN (-5075 3175) $PN G11
J 2
(-5085 3185);
DISPLAY 0.617021 (-5085 3185);
PAINT ORANGE (-5085 3185);
FORCEPROP 2 LASTPIN (-5075 3225) $PN G14
J 2
(-5085 3235);
DISPLAY 0.617021 (-5085 3235);
PAINT ORANGE (-5085 3235);
FORCEPROP 2 LASTPIN (-5075 3425) $PN F12
J 2
(-5085 3435);
DISPLAY 0.617021 (-5085 3435);
PAINT ORANGE (-5085 3435);
FORCEPROP 2 LASTPIN (-5075 3475) $PN F16
J 2
(-5085 3485);
DISPLAY 0.617021 (-5085 3485);
PAINT ORANGE (-5085 3485);
FORCEPROP 2 LASTPIN (-5075 3925) $PN D15
J 2
(-5085 3935);
DISPLAY 0.617021 (-5085 3935);
PAINT ORANGE (-5085 3935);
FORCEPROP 2 LASTPIN (-5075 4025) $PN E14
J 2
(-5085 4035);
DISPLAY 0.617021 (-5085 4035);
PAINT ORANGE (-5085 4035);
FORCEPROP 2 LASTPIN (-5075 4075) $PN D16
J 2
(-5085 4085);
DISPLAY 0.617021 (-5085 4085);
PAINT ORANGE (-5085 4085);
FORCEPROP 2 LASTPIN (-5075 4175) $PN B16
J 2
(-5085 4185);
DISPLAY 0.617021 (-5085 4185);
PAINT ORANGE (-5085 4185);
FORCEPROP 2 LASTPIN (-5075 4225) $PN C15
J 2
(-5085 4235);
DISPLAY 0.617021 (-5085 4235);
PAINT ORANGE (-5085 4235);
FORCEPROP 2 LASTPIN (-3875 1375) $PN B12
J 0
(-3865 1385);
DISPLAY 0.617021 (-3865 1385);
PAINT ORANGE (-3865 1385);
FORCEPROP 2 LASTPIN (-5075 3675) $PN F13
J 2
(-5085 3685);
DISPLAY 0.617021 (-5085 3685);
PAINT ORANGE (-5085 3685);
FORCEPROP 2 LASTPIN (-5075 3975) $PN C16
J 2
(-5085 3985);
DISPLAY 0.617021 (-5085 3985);
PAINT ORANGE (-5085 3985);
FORCEPROP 2 LASTPIN (-5075 3625) $PN G12
J 2
(-5085 3635);
DISPLAY 0.617021 (-5085 3635);
PAINT ORANGE (-5085 3635);
FORCEPROP 2 LASTPIN (-3875 2575) $PN A9
J 0
(-3865 2585);
DISPLAY 0.617021 (-3865 2585);
PAINT ORANGE (-3865 2585);
FORCEPROP 2 LASTPIN (-3875 2175) $PN D10
J 0
(-3865 2185);
DISPLAY 0.617021 (-3865 2185);
PAINT ORANGE (-3865 2185);
FORCEPROP 2 LASTPIN (-3875 2125) $PN E10
J 0
(-3865 2135);
DISPLAY 0.617021 (-3865 2135);
PAINT ORANGE (-3865 2135);
FORCEPROP 2 LASTPIN (-5075 3725) $PN F15
J 2
(-5085 3735);
DISPLAY 0.617021 (-5085 3735);
PAINT ORANGE (-5085 3735);
FORCEPROP 2 LASTPIN (-5075 3775) $PN E16
J 2
(-5085 3785);
DISPLAY 0.617021 (-5085 3785);
PAINT ORANGE (-5085 3785);
FORCEPROP 1 LAST PACK_TYPE 256BGA
J 0
(-5050 4550);
PAINT SKYBLUE (-5050 4550);
DISPLAY INVISIBLE (-5050 4550);
FORCEPROP 2 LAST ROOM CPLD
J 0
(-5025 4600);
DISPLAY 1.361702 (-5025 4600);
PAINT ORANGE (-5025 4600);
DISPLAY INVISIBLE (-5025 4600);
FORCEPROP 2 LAST SEC_TYPE 256BGA
J 0
(-5025 4550);
DISPLAY 1.021277 (-5025 4550);
PAINT ORANGE (-5025 4550);
DISPLAY INVISIBLE (-5025 4550);
FORCEPROP 2 LAST SEC 2
J 0
(-5025 4550);
DISPLAY 0.680851 (-5025 4550);
PAINT MONO (-5025 4550);
DISPLAY INVISIBLE (-5025 4550);
FORCEPROP 2 LAST CDS_LIB mstr_memory
J 0
(-4475 2725);
PAINT ORANGE (-4475 2725);
DISPLAY INVISIBLE (-4475 2725);
FORCEPROP 1 LAST CDS_LMAN_SYM_OUTLINE -550,1700,550,-1700
J 0
(-4475 2725);
DISPLAY 0.468085 (-4475 2725);
PAINT GREEN (-4475 2725);
DISPLAY INVISIBLE (-4475 2725);
FORCEPROP 1 LAST PATH I59
J 0
(-4100 4450);
PAINT GREEN (-4100 4450);
DISPLAY INVISIBLE (-4100 4450);
FORCEPROP 2 LAST CDS_LOCATION U8D7
J 0
(-5049 4501);
DISPLAY 0.617021 (-5049 4501);
PAINT AQUA (-5049 4501);
DISPLAY INVISIBLE (-5049 4501);
FORCEPROP 2 LAST BOM_COST CPLD
J 0
(-5025 4700);
DISPLAY 1.361702 (-5025 4700);
PAINT ORANGE (-5025 4700);
DISPLAY INVISIBLE (-5025 4700);
FORCEADD OFFPAGE..4
R 2
(-6425 3375);
FORCEPROP 2 LAST $XR0 92 
J 0
(-6676 3375);
DISPLAY 0.638298 (-6676 3375);
PAINT MONO (-6676 3375);
FORCEPROP 2 LAST CDS_LIB mstr_standard
J 0
(-6425 3375);
PAINT ORANGE (-6425 3375);
DISPLAY INVISIBLE (-6425 3375);
FORCEPROP 1 LAST OFFPAGE TRUE
J 2
(-6750 3250);
DISPLAY 1.170213 (-6750 3250);
PAINT GREEN (-6750 3250);
DISPLAY INVISIBLE (-6750 3250);
FORCEPROP 1 LAST COMMENT_BODY TRUE
J 2
(-6400 3275);
DISPLAY 1.170213 (-6400 3275);
PAINT GREEN (-6400 3275);
DISPLAY INVISIBLE (-6400 3275);
FORCEPROP 2 LAST PATH I84
J 0
(-6375 3450);
DISPLAY 1.021277 (-6375 3450);
PAINT ORANGE (-6375 3450);
DISPLAY INVISIBLE (-6375 3450);
FORCEADD OFFPAGE..2
R 2
(-6425 1175);
FORCEPROP 2 LAST $XR1 232 
J 0
(-6800 1175);
DISPLAY 0.638298 (-6800 1175);
PAINT MONO (-6800 1175);
FORCEPROP 2 LAST $XR0 231 
J 0
(-6680 1175);
DISPLAY 0.638298 (-6680 1175);
PAINT MONO (-6680 1175);
FORCEPROP 2 LAST CDS_LIB mstr_standard
J 0
(-6425 1175);
PAINT ORANGE (-6425 1175);
DISPLAY INVISIBLE (-6425 1175);
FORCEPROP 1 LAST OFFPAGE TRUE
J 2
(-6750 1050);
DISPLAY 1.170213 (-6750 1050);
PAINT GREEN (-6750 1050);
DISPLAY INVISIBLE (-6750 1050);
FORCEPROP 1 LAST COMMENT_BODY TRUE
J 2
(-6380 1080);
DISPLAY 1.170213 (-6380 1080);
PAINT GREEN (-6380 1080);
DISPLAY INVISIBLE (-6380 1080);
FORCEPROP 2 LAST PATH I87
J 0
(-6375 1250);
DISPLAY 1.021277 (-6375 1250);
PAINT ORANGE (-6375 1250);
DISPLAY INVISIBLE (-6375 1250);
FORCEADD OFFPAGE..2
R 2
(-6425 1125);
FORCEPROP 2 LAST $XR0 198 
J 0
(-6680 1125);
DISPLAY 0.638298 (-6680 1125);
PAINT MONO (-6680 1125);
FORCEPROP 2 LAST CDS_LIB mstr_standard
J 0
(-6425 1125);
PAINT ORANGE (-6425 1125);
DISPLAY INVISIBLE (-6425 1125);
FORCEPROP 1 LAST OFFPAGE TRUE
J 2
(-6750 1000);
DISPLAY 1.170213 (-6750 1000);
PAINT GREEN (-6750 1000);
DISPLAY INVISIBLE (-6750 1000);
FORCEPROP 1 LAST COMMENT_BODY TRUE
J 2
(-6380 1030);
DISPLAY 1.170213 (-6380 1030);
PAINT GREEN (-6380 1030);
DISPLAY INVISIBLE (-6380 1030);
FORCEPROP 2 LAST PATH I88
J 0
(-6375 1200);
DISPLAY 1.021277 (-6375 1200);
PAINT ORANGE (-6375 1200);
DISPLAY INVISIBLE (-6375 1200);
FORCEADD OFFPAGE..4
R 2
(-6425 1525);
FORCEPROP 2 LAST $XR0 55 
J 0
(-6646 1525);
DISPLAY 0.638298 (-6646 1525);
PAINT MONO (-6646 1525);
FORCEPROP 2 LAST CDS_LIB mstr_standard
J 0
(-6425 1525);
PAINT ORANGE (-6425 1525);
DISPLAY INVISIBLE (-6425 1525);
FORCEPROP 1 LAST OFFPAGE TRUE
J 2
(-6750 1400);
DISPLAY 1.170213 (-6750 1400);
PAINT GREEN (-6750 1400);
DISPLAY INVISIBLE (-6750 1400);
FORCEPROP 1 LAST COMMENT_BODY TRUE
J 2
(-6400 1425);
DISPLAY 1.170213 (-6400 1425);
PAINT GREEN (-6400 1425);
DISPLAY INVISIBLE (-6400 1425);
FORCEPROP 2 LAST PATH I93
J 0
(-6375 1600);
DISPLAY 1.021277 (-6375 1600);
PAINT ORANGE (-6375 1600);
DISPLAY INVISIBLE (-6375 1600);
FORCEADD OFFPAGE..4
R 2
(-6425 1725);
FORCEPROP 2 LAST $XR0 92 
J 0
(-6676 1725);
DISPLAY 0.638298 (-6676 1725);
PAINT MONO (-6676 1725);
FORCEPROP 2 LAST CDS_LIB mstr_standard
J 0
(-6425 1725);
PAINT ORANGE (-6425 1725);
DISPLAY INVISIBLE (-6425 1725);
FORCEPROP 1 LAST OFFPAGE TRUE
J 2
(-6750 1600);
DISPLAY 1.170213 (-6750 1600);
PAINT GREEN (-6750 1600);
DISPLAY INVISIBLE (-6750 1600);
FORCEPROP 1 LAST COMMENT_BODY TRUE
J 2
(-6400 1625);
DISPLAY 1.170213 (-6400 1625);
PAINT GREEN (-6400 1625);
DISPLAY INVISIBLE (-6400 1625);
FORCEPROP 2 LAST PATH I95
J 0
(-6375 1800);
DISPLAY 1.021277 (-6375 1800);
PAINT ORANGE (-6375 1800);
DISPLAY INVISIBLE (-6375 1800);
FORCEADD OFFPAGE..2
R 2
(-6425 1675);
FORCEPROP 2 LAST $XR3 184 
J 0
(-7040 1675);
DISPLAY 0.638298 (-7040 1675);
PAINT MONO (-7040 1675);
FORCEPROP 2 LAST $XR2 145 
J 0
(-6920 1675);
DISPLAY 0.638298 (-6920 1675);
PAINT MONO (-6920 1675);
FORCEPROP 2 LAST $XR1 134 
J 0
(-6800 1675);
DISPLAY 0.638298 (-6800 1675);
PAINT MONO (-6800 1675);
FORCEPROP 2 LAST $XR0 146 
J 0
(-6680 1675);
DISPLAY 0.638298 (-6680 1675);
PAINT MONO (-6680 1675);
FORCEPROP 2 LAST CDS_LIB mstr_standard
J 0
(-6425 1675);
PAINT ORANGE (-6425 1675);
DISPLAY INVISIBLE (-6425 1675);
FORCEPROP 1 LAST OFFPAGE TRUE
J 2
(-6750 1550);
DISPLAY 1.170213 (-6750 1550);
PAINT GREEN (-6750 1550);
DISPLAY INVISIBLE (-6750 1550);
FORCEPROP 1 LAST COMMENT_BODY TRUE
J 2
(-6380 1580);
DISPLAY 1.170213 (-6380 1580);
PAINT GREEN (-6380 1580);
DISPLAY INVISIBLE (-6380 1580);
FORCEPROP 2 LAST PATH I96
J 0
(-6375 1750);
DISPLAY 1.021277 (-6375 1750);
PAINT ORANGE (-6375 1750);
DISPLAY INVISIBLE (-6375 1750);
FORCEADD OFFPAGE..2
R 2
(-6425 1775);
FORCEPROP 2 LAST $XR0 134 
J 0
(-6680 1775);
DISPLAY 0.638298 (-6680 1775);
PAINT MONO (-6680 1775);
FORCEPROP 2 LAST CDS_LIB mstr_standard
J 0
(-6425 1775);
PAINT ORANGE (-6425 1775);
DISPLAY INVISIBLE (-6425 1775);
FORCEPROP 1 LAST OFFPAGE TRUE
J 2
(-6750 1650);
DISPLAY 1.170213 (-6750 1650);
PAINT GREEN (-6750 1650);
DISPLAY INVISIBLE (-6750 1650);
FORCEPROP 1 LAST COMMENT_BODY TRUE
J 2
(-6380 1680);
DISPLAY 1.170213 (-6380 1680);
PAINT GREEN (-6380 1680);
DISPLAY INVISIBLE (-6380 1680);
FORCEPROP 2 LAST PATH I97
J 0
(-6375 1850);
DISPLAY 1.021277 (-6375 1850);
PAINT ORANGE (-6375 1850);
DISPLAY INVISIBLE (-6375 1850);
FORCEADD OFFPAGE..4
R 2
(-6425 1925);
FORCEPROP 2 LAST $XR1 156 
J 0
(-6766 1925);
DISPLAY 0.638298 (-6766 1925);
PAINT MONO (-6766 1925);
FORCEPROP 2 LAST $XR0 94 
J 0
(-6646 1925);
DISPLAY 0.638298 (-6646 1925);
PAINT MONO (-6646 1925);
FORCEPROP 2 LAST CDS_LIB mstr_standard
J 0
(-6425 1925);
PAINT ORANGE (-6425 1925);
DISPLAY INVISIBLE (-6425 1925);
FORCEPROP 1 LAST OFFPAGE TRUE
J 2
(-6750 1800);
DISPLAY 1.170213 (-6750 1800);
PAINT GREEN (-6750 1800);
DISPLAY INVISIBLE (-6750 1800);
FORCEPROP 1 LAST COMMENT_BODY TRUE
J 2
(-6400 1825);
DISPLAY 1.170213 (-6400 1825);
PAINT GREEN (-6400 1825);
DISPLAY INVISIBLE (-6400 1825);
FORCEPROP 2 LAST PATH I99
J 0
(-6375 2000);
DISPLAY 1.021277 (-6375 2000);
PAINT ORANGE (-6375 2000);
DISPLAY INVISIBLE (-6375 2000);
FORCEADD DESIGN_NOTE..1
(-4800 775);
FORCEPROP 0 LAST L1 SMBUS ADDRESSES:  0X80-0X86
J 0
(-5000 650);
DISPLAY 1.021277 (-5000 650);
PAINT ORANGE (-5000 650);
FORCEPROP 1 LAST COMMENT_BODY TRUE
J 0
(-4775 875);
DISPLAY 0.978723 (-4775 875);
PAINT ORANGE (-4775 875);
DISPLAY INVISIBLE (-4775 875);
FORCEPROP 2 LAST CDS_LIB mstr_symbols
J 0
(-4800 775);
PAINT ORANGE (-4800 775);
DISPLAY INVISIBLE (-4800 775);
FORCEADD CAD_NOTE..1
(-1775 2900);
FORCEPROP 0 LAST L1 PLACE THIS RESISTOR NEAR CPLD
J 0
(-1925 2750);
DISPLAY 1.021277 (-1925 2750);
PAINT ORANGE (-1925 2750);
FORCEPROP 1 LAST COMMENT_BODY TRUE
J 0
(-1750 3000);
DISPLAY 0.978723 (-1750 3000);
PAINT ORANGE (-1750 3000);
DISPLAY INVISIBLE (-1750 3000);
FORCEPROP 2 LAST CDS_LIB mstr_symbols
J 0
(-1775 2900);
PAINT MONO (-1775 2900);
DISPLAY INVISIBLE (-1775 2900);
FORCEADD INTEL_CORP_BPAGE..1
(-200 25);
FORCEPROP 1 LAST CDS_CON_LAST_MODIFIED Fri Jun 16 17:49:10 2017
J 0
(-1625 350);
PAINT ORANGE (-1625 350);
DISPLAY INVISIBLE (-1625 350);
FORCEPROP 2 LAST CUSTOM_TXT_CDS <XR_PAGE_TITLE>
J 0
(-8090 5275);
DISPLAY 0.638298 (-8090 5275);
PAINT PINK (-8090 5275);
DISPLAY INVISIBLE (-8090 5275);
FORCEPROP 2 LAST CUSTOM_TXT_CDS <CON_LAST_MODIFIED>
J 0
(-4200 125);
PAINT ORANGE (-4200 125);
FORCEPROP 2 LAST CUSTOM_TXT_CDS <CURRENT_DESIGN_SHEET> OF <TOTAL_DESIGN_SHEETS>
J 0
(-700 50);
PAINT ORANGE (-700 50);
FORCEPROP 1 LAST SCH_TITLE CPLD (2 OF 3)
J 0
(-8150 75);
DISPLAY 1.212766 (-8150 75);
PAINT ORANGE (-8150 75);
FORCEPROP 2 LAST CDS_LIB mstr_symbols
J 0
(-200 25);
PAINT ORANGE (-200 25);
DISPLAY INVISIBLE (-200 25);
FORCEPROP 2 LAST PAGE_BORDER TRUE
J 0
(-8090 5275);
DISPLAY 0.638298 (-8090 5275);
PAINT PINK (-8090 5275);
DISPLAY INVISIBLE (-8090 5275);
FORCEPROP 1 LAST COMMENT_BODY TRUE
J 0
(-188 37);
DISPLAY 0.468085 (-188 37);
PAINT GREEN (-188 37);
DISPLAY INVISIBLE (-188 37);
FORCEPROP 2 LAST CDS_XR_PAGE_TITLE CR-191 : @BASEBOARD_FAB2_LIB.BASEBOARD_FAB2(SCH_1):PAGE191
J 0
(-8090 5275);
DISPLAY 0.638298 (-8090 5275);
PAINT PINK (-8090 5275);
DISPLAY INVISIBLE (-8090 5275);
WIRE 16 -1 (-1375 3650)(-1375 3700);
WIRE 16 -1 (-7225 2850)(-7225 2775);
WIRE 16 -1 (-1700 2375)(-1700 2300);
WIRE 16 -1 (-5075 3975)(-6375 3975);
FORCEPROP 2 LAST SIG_NAME PWRGD_PCH_PWROK
J 0
(-6325 3993);
DISPLAY 0.617021 (-6325 3993);
PAINT ORANGE (-6325 3993);
WIRE 16 -1 (-3875 2425)(-2500 2425);
FORCEPROP 0 LAST SIG_NAME PU_RST_PERST_BIT1
J 0
(-3685 2435);
DISPLAY 0.617021 (-3685 2435);
PAINT ORANGE (-3685 2435);
WIRE 16 -1 (-3875 3075)(-2500 3075);
FORCEPROP 0 LAST SIG_NAME JTAG_PLD_TMS
J 0
(-3085 3085);
DISPLAY 0.617021 (-3085 3085);
PAINT ORANGE (-3085 3085);
WIRE 16 -1 (-5075 4275)(-6375 4275);
FORCEPROP 2 LAST SIG_NAME RST_PLTRST_N
J 0
(-6325 4293);
DISPLAY 0.617021 (-6325 4293);
PAINT ORANGE (-6325 4293);
WIRE 16 -1 (-5075 2925)(-6375 2925);
FORCEPROP 2 LAST SIG_NAME FM_PVDDQ_GHJ_EN
J 0
(-6325 2943);
DISPLAY 0.617021 (-6325 2943);
PAINT ORANGE (-6325 2943);
WIRE 16 -1 (-5075 4175)(-6375 4175);
FORCEPROP 2 LAST SIG_NAME FM_ADR_COMPLETE_DLY
J 0
(-6325 4193);
DISPLAY 0.617021 (-6325 4193);
PAINT ORANGE (-6325 4193);
WIRE 16 -1 (-5075 3025)(-6375 3025);
FORCEPROP 2 LAST SIG_NAME FM_FAST_PROCHOT_THROTTLE_IN_N
J 0
(-6325 3043);
DISPLAY 0.617021 (-6325 3043);
PAINT ORANGE (-6325 3043);
WIRE 16 -1 (-3875 1575)(-3200 1575);
FORCEPROP 2 LAST SIG_NAME TP_CPLD1_PT22C
J 0
(-3750 1593);
DISPLAY 0.617021 (-3750 1593);
PAINT ORANGE (-3750 1593);
FORCEPROP 2 LASTPROP $XRERR UNIQUE?
J 0
(-3170 1575);
DISPLAY 0.638298 (-3170 1575);
PAINT MONO (-3170 1575);
DISPLAY INVISIBLE (-3170 1575);
WIRE 16 -1 (-5075 3275)(-6375 3275);
FORCEPROP 2 LAST SIG_NAME FM_UV_ADR_TRIGGER_N
J 0
(-6325 3293);
DISPLAY 0.617021 (-6325 3293);
PAINT ORANGE (-6325 3293);
WIRE 16 -1 (-5075 3725)(-6375 3725);
FORCEPROP 2 LAST SIG_NAME FM_CPU0_MCP_CLK_EN_N
J 0
(-6325 3735);
DISPLAY 0.617021 (-6325 3735);
PAINT ORANGE (-6325 3735);
WIRE 16 -1 (-3875 2375)(-2500 2375);
FORCEPROP 0 LAST SIG_NAME FM_PVCCIN_PVCCSA_CPU0_EN_LVC1
J 0
(-3690 2385);
DISPLAY 0.617021 (-3690 2385);
PAINT ORANGE (-3690 2385);
WIRE 16 -1 (-5075 3425)(-6375 3425);
FORCEPROP 2 LAST SIG_NAME FM_P1V8MCP_CPU1_EN
J 0
(-6050 3443);
DISPLAY 0.617021 (-6050 3443);
PAINT ORANGE (-6050 3443);
WIRE 16 -1 (-3875 3675)(-2500 3675);
FORCEPROP 0 LAST SIG_NAME PWRGD_P1V15_BMC_STBY
J 0
(-3085 3685);
DISPLAY 0.617021 (-3085 3685);
PAINT ORANGE (-3085 3685);
WIRE 16 -1 (-3875 4275)(-2500 4275);
WIRE 16 -1 (-3875 4225)(-2500 4225);
FORCEPROP 0 LAST SIG_NAME FM_CTNR_PS_ON
J 0
(-3085 4235);
DISPLAY 0.617021 (-3085 4235);
PAINT ORANGE (-3085 4235);
WIRE 16 -1 (-3875 3825)(-2500 3825);
FORCEPROP 0 LAST SIG_NAME PWRGD_PVTT_CPU0
J 0
(-3085 3835);
DISPLAY 0.617021 (-3085 3835);
PAINT ORANGE (-3085 3835);
WIRE 16 -1 (-1375 3450)(-1375 3325);
WIRE 16 -1 (-1375 3325)(-900 3325);
FORCEPROP 0 LAST SIG_NAME FM_FORCE_ADR_N
J 2
(-910 3335);
DISPLAY 0.617021 (-910 3335);
PAINT ORANGE (-910 3335);
WIRE 16 -1 (-3875 3325)(-1375 3325);
WIRE 16 -1 (-3875 2825)(-2500 2825);
FORCEPROP 0 LAST SIG_NAME FM_SLP_SUS_N
J 0
(-3085 2835);
DISPLAY 0.617021 (-3085 2835);
PAINT ORANGE (-3085 2835);
WIRE 16 -1 (-3875 2325)(-2500 2325);
FORCEPROP 0 LAST SIG_NAME FM_PS_EN
J 0
(-3685 2335);
DISPLAY 0.617021 (-3685 2335);
PAINT ORANGE (-3685 2335);
WIRE 3 682 (-1950 1950)(-1375 1950);
WIRE 3 682 (-1950 2550)(-1950 1950);
WIRE 3 682 (-1375 1950)(-1375 2550);
WIRE 3 682 (-1375 2550)(-1950 2550);
WIRE 16 -1 (-1700 2025)(-3875 2025);
FORCEPROP 2 LAST SIG_NAME PU_CPLD1_PT20D_PROGRAMN
J 0
(-3685 2035);
DISPLAY 0.638298 (-3685 2035);
PAINT ORANGE (-3685 2035);
FORCEPROP 2 LASTPROP $XRERR UNIQUE?
J 0
(-3925 2035);
DISPLAY 0.638298 (-3925 2035);
PAINT MONO (-3925 2035);
DISPLAY INVISIBLE (-3925 2035);
WIRE 16 -1 (-1700 2100)(-1700 2025);
WIRE 16 -1 (-3875 2675)(-1525 2675);
FORCEPROP 0 LAST SIG_NAME SGPIO_BMC_DIN_R
J 0
(-3685 2675);
DISPLAY 0.617021 (-3685 2675);
PAINT ORANGE (-3685 2675);
FORCEPROP 2 LASTPROP $XRERR UNIQUE?
J 0
(-3925 2675);
DISPLAY 0.638298 (-3925 2675);
PAINT MONO (-3925 2675);
DISPLAY INVISIBLE (-3925 2675);
WIRE 16 -1 (-3875 2625)(-2500 2625);
FORCEPROP 0 LAST SIG_NAME RST_PCIE_MIDPLANE_N
J 0
(-3685 2635);
DISPLAY 0.617021 (-3685 2635);
PAINT ORANGE (-3685 2635);
WIRE 16 -1 (-3875 2575)(-2500 2575);
FORCEPROP 0 LAST SIG_NAME SMB_SENSOR_STBY_LVC3_SCL
J 0
(-3685 2585);
DISPLAY 0.617021 (-3685 2585);
PAINT ORANGE (-3685 2585);
WIRE 16 -1 (-3875 2525)(-2500 2525);
FORCEPROP 0 LAST SIG_NAME SMB_SENSOR_STBY_LVC3_SDA
J 0
(-3685 2535);
DISPLAY 0.617021 (-3685 2535);
PAINT ORANGE (-3685 2535);
WIRE 16 -1 (-5075 4325)(-6375 4325);
FORCEPROP 2 LAST SIG_NAME PWRGD_SYS_PWROK
J 0
(-6325 4343);
DISPLAY 0.617021 (-6325 4343);
PAINT ORANGE (-6325 4343);
WIRE 16 -1 (-5075 4225)(-6375 4225);
FORCEPROP 2 LAST SIG_NAME FM_DB1200_PWRGD
J 0
(-6325 4243);
DISPLAY 0.617021 (-6325 4243);
PAINT ORANGE (-6325 4243);
WIRE 16 -1 (-5075 4075)(-6375 4075);
FORCEPROP 2 LAST SIG_NAME PWRGD_P1V8MCP_CPU1
J 0
(-6325 4093);
DISPLAY 0.617021 (-6325 4093);
PAINT ORANGE (-6325 4093);
WIRE 16 -1 (-6375 4025)(-5075 4025);
FORCEPROP 0 LAST SIG_NAME FM_CPLD_ADR_TRIGGER_N
J 0
(-6325 4035);
DISPLAY 0.617021 (-6325 4035);
PAINT ORANGE (-6325 4035);
WIRE 16 -1 (-5075 3925)(-6375 3925);
FORCEPROP 2 LAST SIG_NAME PWRGD_P1V8MCP_CPU0
J 0
(-6325 3943);
DISPLAY 0.617021 (-6325 3943);
PAINT ORANGE (-6325 3943);
WIRE 16 -1 (-5075 3775)(-6375 3775);
FORCEPROP 2 LAST SIG_NAME FM_P1V8MCP_CPU0_EN
J 0
(-6325 3793);
DISPLAY 0.617021 (-6325 3793);
PAINT ORANGE (-6325 3793);
WIRE 16 -1 (-5075 3625)(-6375 3625);
FORCEPROP 2 LAST SIG_NAME FM_CPU0_THERMTRIP_LATCH_LVT3_N
J 0
(-6325 3643);
DISPLAY 0.617021 (-6325 3643);
PAINT ORANGE (-6325 3643);
WIRE 16 -1 (-5075 3675)(-6375 3675);
FORCEPROP 2 LAST SIG_NAME PWRGD_CPUPWRGD
J 0
(-6325 3693);
DISPLAY 0.617021 (-6325 3693);
PAINT ORANGE (-6325 3693);
WIRE 3 682 (-6200 3500)(-6200 3350);
WIRE 3 682 (-6200 3350)(-5800 3350);
WIRE 16 -1 (-5075 3225)(-6375 3225);
FORCEPROP 2 LAST SIG_NAME FM_CPU1_THERMTRIP_LVT3_N
J 0
(-6325 3243);
DISPLAY 0.617021 (-6325 3243);
PAINT ORANGE (-6325 3243);
WIRE 16 -1 (-5075 3125)(-6375 3125);
FORCEPROP 2 LAST SIG_NAME FM_UV_ADR_TRIGGER_EN
J 0
(-6325 3143);
DISPLAY 0.617021 (-6325 3143);
PAINT ORANGE (-6325 3143);
WIRE 16 -1 (-5075 2975)(-6375 2975);
FORCEPROP 2 LAST SIG_NAME FM_PVDDQ_KLM_EN
J 0
(-6325 2993);
DISPLAY 0.617021 (-6325 2993);
PAINT ORANGE (-6325 2993);
WIRE 16 -1 (-5075 3525)(-6100 3525);
FORCEPROP 2 LAST SIG_NAME RST_BMC_SYSRST_BTN_OUT_B_R1_N
J 0
(-6050 3543);
DISPLAY 0.617021 (-6050 3543);
PAINT ORANGE (-6050 3543);
FORCEPROP 2 LASTPROP $XRERR UNIQUE?
J 0
(-6290 3543);
DISPLAY 0.638298 (-6290 3543);
PAINT MONO (-6290 3543);
DISPLAY INVISIBLE (-6290 3543);
WIRE 16 -1 (-6300 3525)(-7150 3525);
FORCEPROP 2 LAST SIG_NAME RST_BMC_SYSRST_BTN_OUT_B_N
J 0
(-7100 3543);
DISPLAY 0.617021 (-7100 3543);
PAINT ORANGE (-7100 3543);
WIRE 16 -1 (-7225 2575)(-7225 2475);
WIRE 16 -1 (-5075 2475)(-7225 2475);
FORCEPROP 2 LAST SIG_NAME PU_FAB2_MARKER_CPLD
J 0
(-5941 2493);
DISPLAY 0.617021 (-5941 2493);
PAINT ORANGE (-5941 2493);
FORCEPROP 2 LASTPROP $XRERR UNIQUE?
J 0
(-6181 2493);
DISPLAY 0.638298 (-6181 2493);
PAINT MONO (-6181 2493);
DISPLAY INVISIBLE (-6181 2493);
WIRE 16 -1 (-3875 4125)(-2500 4125);
FORCEPROP 0 LAST SIG_NAME FM_P3V3_CPLD_EN
J 0
(-3085 4135);
DISPLAY 0.617021 (-3085 4135);
PAINT ORANGE (-3085 4135);
WIRE 16 -1 (-3875 4075)(-2500 4075);
FORCEPROP 0 LAST SIG_NAME FM_CPU1_THERMTRIP_LATCH_LVT3_N
J 0
(-3235 4085);
DISPLAY 0.617021 (-3235 4085);
PAINT ORANGE (-3235 4085);
WIRE 16 -1 (-3875 3925)(-3150 3925);
FORCEPROP 0 LAST SIG_NAME TP_CPLD1_PT11B
J 0
(-3690 3935);
DISPLAY 0.617021 (-3690 3935);
PAINT ORANGE (-3690 3935);
FORCEPROP 2 LASTPROP $XRERR UNIQUE?
J 0
(-3120 3925);
DISPLAY 0.638298 (-3120 3925);
PAINT MONO (-3120 3925);
DISPLAY INVISIBLE (-3120 3925);
WIRE 16 -1 (-3875 3875)(-2500 3875);
FORCEPROP 0 LAST SIG_NAME FM_PCH_PRSNT_N
J 0
(-3085 3885);
DISPLAY 0.617021 (-3085 3885);
PAINT ORANGE (-3085 3885);
WIRE 16 -1 (-3875 3725)(-2500 3725);
FORCEPROP 0 LAST SIG_NAME RST_PCIE_CPU_DEV0_N
J 0
(-3085 3735);
DISPLAY 0.617021 (-3085 3735);
PAINT ORANGE (-3085 3735);
WIRE 16 -1 (-3875 3625)(-2500 3625);
FORCEPROP 0 LAST SIG_NAME JTAG_PLD_TDO
J 0
(-3085 3635);
DISPLAY 0.617021 (-3085 3635);
PAINT ORANGE (-3085 3635);
WIRE 16 -1 (-3875 3575)(-2500 3575);
FORCEPROP 0 LAST SIG_NAME JTAG_PLD_TDI
J 0
(-3085 3585);
DISPLAY 0.617021 (-3085 3585);
PAINT ORANGE (-3085 3585);
WIRE 16 -1 (-3875 4325)(-3275 4325);
FORCEPROP 2 LAST SIG_NAME FM_ADR_SMI_GPIO_R_N
J 0
(-3785 4335);
DISPLAY 0.617021 (-3785 4335);
PAINT ORANGE (-3785 4335);
FORCEPROP 2 LASTPROP $XRERR UNIQUE?
J 0
(-4025 4335);
DISPLAY 0.638298 (-4025 4335);
PAINT MONO (-4025 4335);
DISPLAY INVISIBLE (-4025 4335);
WIRE 16 -1 (-5075 3375)(-6375 3375);
FORCEPROP 2 LAST SIG_NAME FM_CPU1_FIVR_FAULT_LVT3
J 0
(-6050 3393);
DISPLAY 0.617021 (-6050 3393);
PAINT ORANGE (-6050 3393);
WIRE 16 -1 (-5075 3475)(-6375 3475);
FORCEPROP 2 LAST SIG_NAME FM_CPU1_MCP_CLK_EN_N
J 0
(-6050 3485);
DISPLAY 0.617021 (-6050 3485);
PAINT ORANGE (-6050 3485);
WIRE 16 -1 (-5075 3175)(-6375 3175);
FORCEPROP 2 LAST SIG_NAME FM_WBG_PRSNT_N
J 0
(-6325 3193);
DISPLAY 0.617021 (-6325 3193);
PAINT ORANGE (-6325 3193);
WIRE 16 -1 (-3875 1825)(-2500 1825);
FORCEPROP 0 LAST SIG_NAME FM_CPU1_CD_PRES_N
J 0
(-3075 1835);
DISPLAY 0.617021 (-3075 1835);
PAINT ORANGE (-3075 1835);
WIRE 16 -1 (-3875 1875)(-2500 1875);
FORCEPROP 0 LAST SIG_NAME FM_CPU0_CD_PRES
J 0
(-3075 1885);
DISPLAY 0.617021 (-3075 1885);
PAINT ORANGE (-3075 1885);
WIRE 16 -1 (-3875 1925)(-2500 1925);
FORCEPROP 0 LAST SIG_NAME FM_CPU0_OR_CPU1_MCP_PRES
J 0
(-3075 1935);
DISPLAY 0.617021 (-3075 1935);
PAINT ORANGE (-3075 1935);
WIRE 16 -1 (-3875 2075)(-2500 2075);
FORCEPROP 2 LAST SIG_NAME FM_JTAG_PLD_EN_DEBUG
J 0
(-3085 2093);
DISPLAY 0.617021 (-3085 2093);
PAINT ORANGE (-3085 2093);
WIRE 16 -1 (-3875 1375)(-3200 1375);
FORCEPROP 2 LAST SIG_NAME FM_PCH_PWRBTN_R1_N
J 0
(-3735 1393);
DISPLAY 0.617021 (-3735 1393);
PAINT ORANGE (-3735 1393);
FORCEPROP 2 LASTPROP $XRERR UNIQUE?
J 0
(-3975 1393);
DISPLAY 0.638298 (-3975 1393);
PAINT MONO (-3975 1393);
DISPLAY INVISIBLE (-3975 1393);
WIRE 16 -1 (-3875 1525)(-3200 1525);
FORCEPROP 0 LAST SIG_NAME TP_CPLD1_PT22D
J 0
(-3750 1535);
DISPLAY 0.617021 (-3750 1535);
PAINT ORANGE (-3750 1535);
FORCEPROP 2 LASTPROP $XRERR UNIQUE?
J 0
(-3170 1525);
DISPLAY 0.638298 (-3170 1525);
PAINT MONO (-3170 1525);
DISPLAY INVISIBLE (-3170 1525);
WIRE 16 -1 (-3875 2125)(-3175 2125);
FORCEPROP 0 LAST SIG_NAME TP_CPLD1_PT20B
J 0
(-3700 2135);
DISPLAY 0.617021 (-3700 2135);
PAINT ORANGE (-3700 2135);
FORCEPROP 2 LASTPROP $XRERR UNIQUE?
J 0
(-3145 2125);
DISPLAY 0.638298 (-3145 2125);
PAINT MONO (-3145 2125);
DISPLAY INVISIBLE (-3145 2125);
WIRE 16 -1 (-3875 2175)(-3175 2175);
FORCEPROP 0 LAST SIG_NAME TP_CPLD1_PT20A
J 0
(-3700 2185);
DISPLAY 0.617021 (-3700 2185);
PAINT ORANGE (-3700 2185);
FORCEPROP 2 LASTPROP $XRERR UNIQUE?
J 0
(-3145 2175);
DISPLAY 0.638298 (-3145 2175);
PAINT MONO (-3145 2175);
DISPLAY INVISIBLE (-3145 2175);
WIRE 16 -1 (-3875 2275)(-3175 2275);
FORCEPROP 0 LAST SIG_NAME TP_CPLD1_PT19D
J 0
(-3700 2285);
DISPLAY 0.617021 (-3700 2285);
PAINT ORANGE (-3700 2285);
FORCEPROP 2 LASTPROP $XRERR UNIQUE?
J 0
(-3145 2275);
DISPLAY 0.638298 (-3145 2275);
PAINT MONO (-3145 2275);
DISPLAY INVISIBLE (-3145 2275);
WIRE 16 -1 (-5075 1925)(-6375 1925);
FORCEPROP 2 LAST SIG_NAME FM_MEM_THERM_EVENT_LVT3_N
J 0
(-6325 1943);
DISPLAY 0.617021 (-6325 1943);
PAINT ORANGE (-6325 1943);
WIRE 16 -1 (-3875 3175)(-3175 3175);
FORCEPROP 0 LAST SIG_NAME TP_CPLD1_PT16B
J 0
(-3690 3185);
DISPLAY 0.617021 (-3690 3185);
PAINT ORANGE (-3690 3185);
FORCEPROP 2 LASTPROP $XRERR UNIQUE?
J 0
(-3145 3175);
DISPLAY 0.638298 (-3145 3175);
PAINT MONO (-3145 3175);
DISPLAY INVISIBLE (-3145 3175);
WIRE 16 -1 (-3875 2925)(-3175 2925);
FORCEPROP 0 LAST SIG_NAME TP_CPLD1_PT17B_PCLKC0_1
J 0
(-3690 2935);
DISPLAY 0.617021 (-3690 2935);
PAINT ORANGE (-3690 2935);
FORCEPROP 2 LASTPROP $XRERR UNIQUE?
J 0
(-2993 2935);
DISPLAY 0.638298 (-2993 2935);
PAINT MONO (-2993 2935);
DISPLAY INVISIBLE (-2993 2935);
WIRE 16 -1 (-3875 2875)(-3175 2875);
FORCEPROP 0 LAST SIG_NAME TP_CPLD1_PT17C
J 0
(-3685 2885);
DISPLAY 0.617021 (-3685 2885);
PAINT ORANGE (-3685 2885);
FORCEPROP 2 LASTPROP $XRERR UNIQUE?
J 0
(-3145 2875);
DISPLAY 0.638298 (-3145 2875);
PAINT MONO (-3145 2875);
DISPLAY INVISIBLE (-3145 2875);
WIRE 16 -1 (-5075 2775)(-6025 2775);
FORCEPROP 2 LAST SIG_NAME TP_CPLD1_PR7A_PCLKT1_0
J 0
(-5941 2793);
DISPLAY 0.617021 (-5941 2793);
PAINT ORANGE (-5941 2793);
FORCEPROP 2 LASTPROP $XRERR UNIQUE?
J 0
(-6265 2775);
DISPLAY 0.638298 (-6265 2775);
PAINT MONO (-6265 2775);
DISPLAY INVISIBLE (-6265 2775);
WIRE 16 -1 (-5075 2725)(-6025 2725);
FORCEPROP 2 LAST SIG_NAME TP_CPLD1_PR7B_PCLKC1_0
J 0
(-5941 2743);
DISPLAY 0.617021 (-5941 2743);
PAINT ORANGE (-5941 2743);
FORCEPROP 2 LASTPROP $XRERR UNIQUE?
J 0
(-6265 2725);
DISPLAY 0.638298 (-6265 2725);
PAINT MONO (-6265 2725);
DISPLAY INVISIBLE (-6265 2725);
WIRE 16 -1 (-5075 2675)(-6025 2675);
FORCEPROP 2 LAST SIG_NAME TP_CPLD1_PR7C
J 0
(-5941 2693);
DISPLAY 0.617021 (-5941 2693);
PAINT ORANGE (-5941 2693);
FORCEPROP 2 LASTPROP $XRERR UNIQUE?
J 0
(-6265 2675);
DISPLAY 0.638298 (-6265 2675);
PAINT MONO (-6265 2675);
DISPLAY INVISIBLE (-6265 2675);
WIRE 16 -1 (-5075 2625)(-6025 2625);
FORCEPROP 2 LAST SIG_NAME TP_CPLD1_PR7D
J 0
(-5941 2643);
DISPLAY 0.617021 (-5941 2643);
PAINT ORANGE (-5941 2643);
FORCEPROP 2 LASTPROP $XRERR UNIQUE?
J 0
(-6265 2625);
DISPLAY 0.638298 (-6265 2625);
PAINT MONO (-6265 2625);
DISPLAY INVISIBLE (-6265 2625);
WIRE 16 -1 (-5075 2525)(-6025 2525);
FORCEPROP 2 LAST SIG_NAME TP_CPLD1_PR9A
J 0
(-5941 2543);
DISPLAY 0.617021 (-5941 2543);
PAINT ORANGE (-5941 2543);
FORCEPROP 2 LASTPROP $XRERR UNIQUE?
J 0
(-6265 2525);
DISPLAY 0.638298 (-6265 2525);
PAINT MONO (-6265 2525);
DISPLAY INVISIBLE (-6265 2525);
WIRE 16 -1 (-5075 2425)(-6025 2425);
FORCEPROP 2 LAST SIG_NAME TP_CPLD1_PR9C
J 0
(-5941 2443);
DISPLAY 0.617021 (-5941 2443);
PAINT ORANGE (-5941 2443);
FORCEPROP 2 LASTPROP $XRERR UNIQUE?
J 0
(-6265 2425);
DISPLAY 0.638298 (-6265 2425);
PAINT MONO (-6265 2425);
DISPLAY INVISIBLE (-6265 2425);
WIRE 16 -1 (-5075 2375)(-6025 2375);
FORCEPROP 2 LAST SIG_NAME TP_CPLD1_PR9D
J 0
(-5941 2393);
DISPLAY 0.617021 (-5941 2393);
PAINT ORANGE (-5941 2393);
FORCEPROP 2 LASTPROP $XRERR UNIQUE?
J 0
(-6265 2375);
DISPLAY 0.638298 (-6265 2375);
PAINT MONO (-6265 2375);
DISPLAY INVISIBLE (-6265 2375);
WIRE 16 -1 (-5075 2175)(-6025 2175);
FORCEPROP 2 LAST SIG_NAME TP_CPLD1_PR10C
J 0
(-5975 2193);
DISPLAY 0.617021 (-5975 2193);
PAINT ORANGE (-5975 2193);
FORCEPROP 2 LASTPROP $XRERR UNIQUE?
J 0
(-6265 2175);
DISPLAY 0.638298 (-6265 2175);
PAINT MONO (-6265 2175);
DISPLAY INVISIBLE (-6265 2175);
WIRE 16 -1 (-5075 1975)(-6025 1975);
FORCEPROP 2 LAST SIG_NAME TP_CPLD1_PR11B
J 0
(-5975 1993);
DISPLAY 0.617021 (-5975 1993);
PAINT ORANGE (-5975 1993);
FORCEPROP 2 LASTPROP $XRERR UNIQUE?
J 0
(-6265 1975);
DISPLAY 0.638298 (-6265 1975);
PAINT MONO (-6265 1975);
DISPLAY INVISIBLE (-6265 1975);
WIRE 16 -1 (-5075 1625)(-5975 1625);
FORCEPROP 2 LAST SIG_NAME TP_CPLD1_PR12D
J 0
(-5941 1643);
DISPLAY 0.617021 (-5941 1643);
PAINT ORANGE (-5941 1643);
FORCEPROP 2 LASTPROP $XRERR UNIQUE?
J 0
(-6215 1625);
DISPLAY 0.638298 (-6215 1625);
PAINT MONO (-6215 1625);
DISPLAY INVISIBLE (-6215 1625);
WIRE 16 -1 (-5075 1475)(-6375 1475);
FORCEPROP 2 LAST SIG_NAME FM_CPU1_PROC_ID0
J 0
(-6325 1493);
DISPLAY 0.617021 (-6325 1493);
PAINT ORANGE (-6325 1493);
WIRE 16 -1 (-5075 1775)(-6375 1775);
FORCEPROP 2 LAST SIG_NAME FM_THERMTRIP_DLY
J 0
(-6325 1793);
DISPLAY 0.617021 (-6325 1793);
PAINT ORANGE (-6325 1793);
WIRE 16 -1 (-5075 1675)(-6375 1675);
FORCEPROP 2 LAST SIG_NAME RST_PLTRST_BUF_N
J 0
(-6325 1693);
DISPLAY 0.617021 (-6325 1693);
PAINT ORANGE (-6325 1693);
WIRE 16 -1 (-5075 1725)(-6375 1725);
FORCEPROP 2 LAST SIG_NAME FM_CPU0_FIVR_FAULT_LVT3
J 0
(-6325 1743);
DISPLAY 0.617021 (-6325 1743);
PAINT ORANGE (-6325 1743);
WIRE 16 -1 (-5075 1525)(-6375 1525);
FORCEPROP 2 LAST SIG_NAME FM_CPU1_PROC_ID1
J 0
(-6325 1543);
DISPLAY 0.617021 (-6325 1543);
PAINT ORANGE (-6325 1543);
WIRE 16 -1 (-5075 1125)(-6375 1125);
FORCEPROP 2 LAST SIG_NAME FM_P12V_MAIN_SW_EN
J 0
(-6325 1143);
DISPLAY 0.617021 (-6325 1143);
PAINT ORANGE (-6325 1143);
WIRE 16 -1 (-5075 1175)(-6375 1175);
FORCEPROP 2 LAST SIG_NAME FM_PVPP_CPU0_EN
J 0
(-6325 1193);
DISPLAY 0.617021 (-6325 1193);
PAINT ORANGE (-6325 1193);
WIRE 16 -1 (-5075 1225)(-6375 1225);
FORCEPROP 2 LAST SIG_NAME FM_CPU1_VRM_OSC_EN
J 0
(-6325 1243);
DISPLAY 0.617021 (-6325 1243);
PAINT ORANGE (-6325 1243);
WIRE 16 -1 (-5075 1275)(-6375 1275);
FORCEPROP 2 LAST SIG_NAME FM_PVCCIN_PVCCSA_CPU1_EN_LVC1
J 0
(-6325 1293);
DISPLAY 0.617021 (-6325 1293);
PAINT ORANGE (-6325 1293);
WIRE 16 -1 (-5075 2025)(-6375 2025);
FORCEPROP 2 LAST SIG_NAME PWRGD_PVCCIO_CPU1
J 0
(-6325 2043);
DISPLAY 0.617021 (-6325 2043);
PAINT ORANGE (-6325 2043);
WIRE 16 -1 (-5075 1875)(-6375 1875);
FORCEPROP 2 LAST SIG_NAME FM_MEM_THERM_EVENT_PCH_N
J 0
(-6325 1893);
DISPLAY 0.617021 (-6325 1893);
PAINT ORANGE (-6325 1893);
WIRE 16 -1 (-5075 2875)(-6375 2875);
FORCEPROP 2 LAST SIG_NAME FM_FAST_PROCHOT_THROTTLE_DLY_N
J 0
(-6325 2893);
DISPLAY 0.617021 (-6325 2893);
PAINT ORANGE (-6325 2893);
WIRE 16 -1 (-5075 2225)(-6375 2225);
FORCEPROP 2 LAST SIG_NAME FM_PVDDQ_DEF_EN
J 0
(-6325 2243);
DISPLAY 0.617021 (-6325 2243);
PAINT ORANGE (-6325 2243);
WIRE 16 -1 (-5075 1425)(-6375 1425);
FORCEPROP 2 LAST SIG_NAME FM_CPU0_THERMTRIP_LVT3_N
J 0
(-6325 1443);
DISPLAY 0.617021 (-6325 1443);
PAINT ORANGE (-6325 1443);
WIRE 16 -1 (-5075 1375)(-6375 1375);
FORCEPROP 2 LAST SIG_NAME FM_PVPP_CPU1_EN
J 0
(-6325 1393);
DISPLAY 0.617021 (-6325 1393);
PAINT ORANGE (-6325 1393);
WIRE 16 -1 (-3875 3225)(-2500 3225);
FORCEPROP 0 LAST SIG_NAME FM_PLD_DEBUG_MODE_N
J 0
(-3085 3235);
DISPLAY 0.617021 (-3085 3235);
PAINT ORANGE (-3085 3235);
WIRE 16 -1 (-3875 3125)(-2500 3125);
FORCEPROP 0 LAST SIG_NAME JTAG_PLD_TCK
J 0
(-3085 3135);
DISPLAY 0.617021 (-3085 3135);
PAINT ORANGE (-3085 3135);
WIRE 16 -1 (-3875 3375)(-2500 3375);
FORCEPROP 0 LAST SIG_NAME FM_CPU1_FIVR_FAULT_LVT3_N
J 0
(-3085 3385);
DISPLAY 0.617021 (-3085 3385);
PAINT ORANGE (-3085 3385);
WIRE 16 -1 (-3875 3475)(-3175 3475);
FORCEPROP 0 LAST SIG_NAME TP_CPLD1_PT13A
J 0
(-3690 3485);
DISPLAY 0.617021 (-3690 3485);
PAINT ORANGE (-3690 3485);
FORCEPROP 2 LASTPROP $XRERR UNIQUE?
J 0
(-3145 3475);
DISPLAY 0.638298 (-3145 3475);
PAINT MONO (-3145 3475);
DISPLAY INVISIBLE (-3145 3475);
WIRE 16 -1 (-2500 4325)(-3075 4325);
FORCEPROP 0 LAST SIG_NAME FM_ADR_SMI_GPIO_N
J 0
(-3035 4335);
DISPLAY 0.617021 (-3035 4335);
PAINT ORANGE (-3035 4335);
WIRE 16 -1 (-5075 2125)(-6375 2125);
FORCEPROP 2 LAST SIG_NAME PWRGD_P3V3_STBY
J 0
(-6325 2143);
DISPLAY 0.617021 (-6325 2143);
PAINT ORANGE (-6325 2143);
WIRE 16 -1 (-5075 2275)(-6375 2275);
FORCEPROP 2 LAST SIG_NAME FM_PVDDQ_ABC_EN
J 0
(-6325 2293);
DISPLAY 0.617021 (-6325 2293);
PAINT ORANGE (-6325 2293);
WIRE 16 -1 (-3875 2975)(-2500 2975);
FORCEPROP 0 LAST SIG_NAME FM_ADR_COMPLETE
J 0
(-3060 2985);
DISPLAY 0.617021 (-3060 2985);
PAINT ORANGE (-3060 2985);
WIRE 16 -1 (-3875 3425)(-2500 3425);
FORCEPROP 0 LAST SIG_NAME FM_BMC_ONCTL_N
J 0
(-3085 3435);
DISPLAY 0.617021 (-3085 3435);
PAINT ORANGE (-3085 3435);
WIRE 16 -1 (-3875 3975)(-3150 3975);
FORCEPROP 0 LAST SIG_NAME TP_CPLD1_PT11A
J 0
(-3690 3985);
DISPLAY 0.617021 (-3690 3985);
PAINT ORANGE (-3690 3985);
FORCEPROP 2 LASTPROP $XRERR UNIQUE?
J 0
(-3120 3975);
DISPLAY 0.638298 (-3120 3975);
PAINT MONO (-3120 3975);
DISPLAY INVISIBLE (-3120 3975);
WIRE 16 -1 (-1325 2675)(-900 2675);
WIRE 16 -1 (-3875 1425)(-2500 1425);
FORCEPROP 0 LAST SIG_NAME FM_SLPS4_N
J 0
(-2985 1435);
DISPLAY 0.617021 (-2985 1435);
PAINT ORANGE (-2985 1435);
WIRE 16 -1 (-3000 1375)(-2500 1375);
FORCEPROP 2 LAST SIG_NAME FM_PCH_PWRBTN_N
J 0
(-2985 1393);
DISPLAY 0.617021 (-2985 1393);
PAINT ORANGE (-2985 1393);
WIRE 16 -1 (-3875 1625)(-2500 1625);
FORCEPROP 2 LAST SIG_NAME PU_THERMTRIP_FORCE_N
J 0
(-3085 1643);
DISPLAY 0.617021 (-3085 1643);
PAINT ORANGE (-3085 1643);
WIRE 16 -1 (-3875 1675)(-2500 1675);
FORCEPROP 0 LAST SIG_NAME PWRGD_DSW_PWROK
J 0
(-3085 1685);
DISPLAY 0.617021 (-3085 1685);
PAINT ORANGE (-3085 1685);
WIRE 16 -1 (-3875 1775)(-2500 1775);
FORCEPROP 0 LAST SIG_NAME FM_CPU0_AND_CPU1_MCP_PRES
J 0
(-3075 1785);
DISPLAY 0.617021 (-3075 1785);
PAINT ORANGE (-3075 1785);
WIRE 16 -1 (-3875 1125)(-3200 1125);
FORCEPROP 2 LAST SIG_NAME TP_CPLD1_PT24D_DONE
J 0
(-3750 1135);
DISPLAY 0.617021 (-3750 1135);
PAINT ORANGE (-3750 1135);
FORCEPROP 2 LASTPROP $XRERR UNIQUE?
J 0
(-3169 1135);
DISPLAY 0.638298 (-3169 1135);
PAINT MONO (-3169 1135);
DISPLAY INVISIBLE (-3169 1135);
WIRE 16 -1 (-3875 1175)(-3200 1175);
FORCEPROP 2 LAST SIG_NAME TP_CPLD1_PT24C_INITN
J 0
(-3750 1185);
DISPLAY 0.617021 (-3750 1185);
PAINT ORANGE (-3750 1185);
FORCEPROP 2 LASTPROP $XRERR UNIQUE?
J 0
(-3140 1185);
DISPLAY 0.638298 (-3140 1185);
PAINT MONO (-3140 1185);
DISPLAY INVISIBLE (-3140 1185);
WIRE 16 -1 (-3875 1225)(-3200 1225);
FORCEPROP 2 LAST SIG_NAME TP_CPLD1_PT24B
J 0
(-3740 1235);
DISPLAY 0.617021 (-3740 1235);
PAINT ORANGE (-3740 1235);
FORCEPROP 2 LASTPROP $XRERR UNIQUE?
J 0
(-3170 1225);
DISPLAY 0.638298 (-3170 1225);
PAINT MONO (-3170 1225);
DISPLAY INVISIBLE (-3170 1225);
WIRE 16 -1 (-3875 1275)(-2500 1275);
FORCEPROP 2 LAST SIG_NAME FM_SINT_PRSNT_N
J 0
(-2985 1285);
DISPLAY 0.617021 (-2985 1285);
PAINT ORANGE (-2985 1285);
DOT 1 (-1375 3325);
FORCENOTE
TP FAB1 ADD RES 0226
(-5775 3325) 0;
DISPLAY LEFT (-5775 3325);
DISPLAY 1.021277 (-5775 3325);
PAINT RED (-5775 3325);
FORCENOTE
BOM_COST CPLD
(-8075 250) 0;
DISPLAY LEFT (-8075 250);
DISPLAY 2.148936 (-8075 250);
PAINT PURPLE (-8075 250);
FORCENOTE
ROOM CPLD
(-8075 400) 0;
DISPLAY LEFT (-8075 400);
DISPLAY 2.148936 (-8075 400);
PAINT PURPLE (-8075 400);
FORCENOTE
TP FAB1 ADD A PU RES 0203
(-1350 1950) 0;
DISPLAY LEFT (-1350 1950);
DISPLAY 1.021277 (-1350 1950);
PAINT RED (-1350 1950);
FORCENOTE
TP FAB1 CHANGE NET NAME TO LOW ACTIVE
(-2150 1825) 0;
DISPLAY LEFT (-2150 1825);
DISPLAY 0.638298 (-2150 1825);
PAINT RED (-2150 1825);
FORCENOTE
TP FAB1 ADD RES 0226
(-3175 1200) 0;
DISPLAY LEFT (-3175 1200);
DISPLAY 1.021277 (-3175 1200);
PAINT RED (-3175 1200);
QUIT
